FILE_TYPE = MACRO_DRAWING;
SET COLOR_WIRE YELLOW;
SET COLOR_PROP MONO;
SET COLOR_DOT WHITE;
SET COLOR_ARC YELLOW;
SET COLOR_BODY GREEN;
SET COLOR_NOTE MONO;
SET PROP_DISPLAY VALUE;
SET PAGE_NUMBER P96;
FORCEADD PVCCIO_CPU0..1
(1800 4700);
FORCEPROP 3 LASTPIN (1800 4650) SIG_NAME PVCCIO_CPU0\g
J 0
(1810 4660);
DISPLAY 0.659574 (1810 4660);
PAINT MONO (1810 4660);
DISPLAY INVISIBLE (1810 4660);
FORCEPROP 1 LAST VOLTAGE 1.1V
J 0
(1755 4657);
DISPLAY 0.340426 (1755 4657);
PAINT SKYBLUE (1755 4657);
DISPLAY INVISIBLE (1755 4657);
FORCEPROP 2 LAST CDS_LIB mstr_symbols
J 0
(1800 4700);
PAINT ORANGE (1800 4700);
DISPLAY INVISIBLE (1800 4700);
FORCEPROP 1 LAST BODY_TYPE PLUMBING
J 0
(1755 4657);
DISPLAY 0.340426 (1755 4657);
PAINT GREEN (1755 4657);
DISPLAY INVISIBLE (1755 4657);
FORCEPROP 1 LAST PATH I1
J 0
(1850 4725);
DISPLAY 0.872340 (1850 4725);
PAINT AQUA (1850 4725);
DISPLAY INVISIBLE (1850 4725);
FORCEPROP 1 LAST HDL_POWER PVCCIO_CPU0
J 1
(1800 4750);
DISPLAY 0.872340 (1800 4750);
PAINT GREEN (1800 4750);
DISPLAY INVISIBLE (1800 4750);
FORCEADD OFFPAGE..2
(3375 3650);
FORCEPROP 2 LAST $XR0 21 
J 0
(3564 3650);
DISPLAY 0.638298 (3564 3650);
PAINT MONO (3564 3650);
FORCEPROP 2 LAST CDS_LIB mstr_standard
J 0
(3375 3650);
PAINT ORANGE (3375 3650);
DISPLAY INVISIBLE (3375 3650);
FORCEPROP 1 LAST OFFPAGE TRUE
J 0
(3700 3525);
DISPLAY 1.404255 (3700 3525);
PAINT GREEN (3700 3525);
DISPLAY INVISIBLE (3700 3525);
FORCEPROP 1 LAST COMMENT_BODY TRUE
J 0
(3330 3555);
DISPLAY 1.404255 (3330 3555);
PAINT PEACH (3330 3555);
DISPLAY INVISIBLE (3330 3555);
FORCEPROP 2 LAST PATH I10
J 0
(3575 3700);
DISPLAY 1.021277 (3575 3700);
PAINT ORANGE (3575 3700);
DISPLAY INVISIBLE (3575 3700);
FORCEADD OFFPAGE..2
(3375 3350);
FORCEPROP 2 LAST $XR0 21 
J 0
(3564 3350);
DISPLAY 0.638298 (3564 3350);
PAINT MONO (3564 3350);
FORCEPROP 2 LAST CDS_LIB mstr_standard
J 0
(3375 3350);
PAINT ORANGE (3375 3350);
DISPLAY INVISIBLE (3375 3350);
FORCEPROP 1 LAST OFFPAGE TRUE
J 0
(3700 3225);
DISPLAY 1.404255 (3700 3225);
PAINT GREEN (3700 3225);
DISPLAY INVISIBLE (3700 3225);
FORCEPROP 1 LAST COMMENT_BODY TRUE
J 0
(3330 3255);
DISPLAY 1.404255 (3330 3255);
PAINT PEACH (3330 3255);
DISPLAY INVISIBLE (3330 3255);
FORCEPROP 2 LAST PATH I11
J 0
(3575 3400);
DISPLAY 1.021277 (3575 3400);
PAINT ORANGE (3575 3400);
DISPLAY INVISIBLE (3575 3400);
FORCEADD OFFPAGE..2
(3375 1800);
FORCEPROP 2 LAST $XR0 55 
J 0
(3564 1800);
DISPLAY 0.638298 (3564 1800);
PAINT MONO (3564 1800);
FORCEPROP 2 LAST CDS_LIB mstr_standard
J 0
(3375 1800);
PAINT ORANGE (3375 1800);
DISPLAY INVISIBLE (3375 1800);
FORCEPROP 1 LAST OFFPAGE TRUE
J 0
(3700 1675);
DISPLAY 1.404255 (3700 1675);
PAINT GREEN (3700 1675);
DISPLAY INVISIBLE (3700 1675);
FORCEPROP 1 LAST COMMENT_BODY TRUE
J 0
(3330 1705);
DISPLAY 1.404255 (3330 1705);
PAINT PEACH (3330 1705);
DISPLAY INVISIBLE (3330 1705);
FORCEPROP 2 LAST PATH I14
J 0
(3575 1850);
DISPLAY 1.021277 (3575 1850);
PAINT ORANGE (3575 1850);
DISPLAY INVISIBLE (3575 1850);
FORCEADD OFFPAGE..2
(3375 1575);
FORCEPROP 2 LAST $XR0 55 
J 0
(3564 1575);
DISPLAY 0.638298 (3564 1575);
PAINT MONO (3564 1575);
FORCEPROP 2 LAST CDS_LIB mstr_standard
J 0
(3375 1575);
PAINT ORANGE (3375 1575);
DISPLAY INVISIBLE (3375 1575);
FORCEPROP 1 LAST OFFPAGE TRUE
J 0
(3700 1450);
DISPLAY 1.404255 (3700 1450);
PAINT GREEN (3700 1450);
DISPLAY INVISIBLE (3700 1450);
FORCEPROP 1 LAST COMMENT_BODY TRUE
J 0
(3330 1480);
DISPLAY 1.404255 (3330 1480);
PAINT PEACH (3330 1480);
DISPLAY INVISIBLE (3330 1480);
FORCEPROP 2 LAST PATH I15
J 0
(3575 1625);
DISPLAY 1.021277 (3575 1625);
PAINT ORANGE (3575 1625);
DISPLAY INVISIBLE (3575 1625);
FORCEADD OFFPAGE..2
(3375 1350);
FORCEPROP 2 LAST $XR0 55 
J 0
(3564 1350);
DISPLAY 0.638298 (3564 1350);
PAINT MONO (3564 1350);
FORCEPROP 2 LAST CDS_LIB mstr_standard
J 0
(3375 1350);
PAINT ORANGE (3375 1350);
DISPLAY INVISIBLE (3375 1350);
FORCEPROP 1 LAST OFFPAGE TRUE
J 0
(3700 1225);
DISPLAY 1.404255 (3700 1225);
PAINT GREEN (3700 1225);
DISPLAY INVISIBLE (3700 1225);
FORCEPROP 1 LAST COMMENT_BODY TRUE
J 0
(3330 1255);
DISPLAY 1.404255 (3330 1255);
PAINT PEACH (3330 1255);
DISPLAY INVISIBLE (3330 1255);
FORCEPROP 2 LAST PATH I16
J 0
(3575 1400);
DISPLAY 1.021277 (3575 1400);
PAINT ORANGE (3575 1400);
DISPLAY INVISIBLE (3575 1400);
FORCEADD OFFPAGE..2
(3375 1050);
FORCEPROP 2 LAST $XR0 55 
J 0
(3564 1050);
DISPLAY 0.638298 (3564 1050);
PAINT MONO (3564 1050);
FORCEPROP 2 LAST CDS_LIB mstr_standard
J 0
(3375 1050);
PAINT ORANGE (3375 1050);
DISPLAY INVISIBLE (3375 1050);
FORCEPROP 1 LAST OFFPAGE TRUE
J 0
(3700 925);
DISPLAY 1.404255 (3700 925);
PAINT GREEN (3700 925);
DISPLAY INVISIBLE (3700 925);
FORCEPROP 1 LAST COMMENT_BODY TRUE
J 0
(3330 955);
DISPLAY 1.404255 (3330 955);
PAINT PEACH (3330 955);
DISPLAY INVISIBLE (3330 955);
FORCEPROP 2 LAST PATH I17
J 0
(3575 1100);
DISPLAY 1.021277 (3575 1100);
PAINT ORANGE (3575 1100);
DISPLAY INVISIBLE (3575 1100);
FORCEADD RES..2
(1900 4450);
FORCEPROP 1 LAST LOCATION R6D12
J 0
(1945 4575);
DISPLAY 0.617021 (1945 4575);
PAINT AQUA (1945 4575);
FORCEPROP 1 LAST PART_NUMBER G21796-047
J 0
(1940 4325);
DISPLAY 0.617021 (1940 4325);
PAINT BLUE (1940 4325);
FORCEPROP 1 LAST VALUE 49.9
J 0
(1945 4525);
DISPLAY 0.617021 (1945 4525);
PAINT SKYBLUE (1945 4525);
FORCEPROP 1 LAST TOLERANCE 1%
J 0
(1945 4475);
DISPLAY 0.617021 (1945 4475);
PAINT SKYBLUE (1945 4475);
FORCEPROP 1 LAST PACK_TYPE 0402
J 0
(1940 4275);
DISPLAY 0.617021 (1940 4275);
PAINT SKYBLUE (1940 4275);
FORCEPROP 1 LAST MATERIAL CHIP
J 0
(1940 4375);
DISPLAY 0.617021 (1940 4375);
PAINT SKYBLUE (1940 4375);
FORCEPROP 1 LAST WATTAGE 1/16W
J 0
(1940 4425);
DISPLAY 0.617021 (1940 4425);
PAINT SKYBLUE (1940 4425);
FORCEPROP 1 LASTPIN (1900 4350) $PN 2
J 0
(1905 4360);
DISPLAY 0.617021 (1905 4360);
PAINT WHITE (1905 4360);
FORCEPROP 1 LASTPIN (1900 4550) $PN 1
J 0
(1905 4512);
DISPLAY 0.617021 (1905 4512);
PAINT WHITE (1905 4512);
FORCEPROP 2 LAST BOM_COST PROC_SIDEBAND
J 0
(1900 4450);
DISPLAY 1.617021 (1900 4450);
PAINT WHITE (1900 4450);
DISPLAY INVISIBLE (1900 4450);
FORCEPROP 2 LAST CDS_LIB mstr_discrete
J 0
(1900 4450);
DISPLAY 1.617021 (1900 4450);
PAINT ORANGE (1900 4450);
DISPLAY INVISIBLE (1900 4450);
FORCEPROP 2 LAST SEC_TYPE 0402
J 0
(1950 4675);
DISPLAY 1.617021 (1950 4675);
PAINT MONO (1950 4675);
DISPLAY INVISIBLE (1950 4675);
FORCEPROP 2 LAST SEC 1
J 0
(1950 4675);
DISPLAY 1.510638 (1950 4675);
PAINT MONO (1950 4675);
DISPLAY INVISIBLE (1950 4675);
FORCEPROP 2 LAST CDS_LOCATION R6D12
J 0
(1945 4575);
DISPLAY 0.617021 (1945 4575);
PAINT AQUA (1945 4575);
DISPLAY INVISIBLE (1945 4575);
FORCEPROP 1 LAST PATH I2
J 0
(1950 4625);
DISPLAY 0.978723 (1950 4625);
PAINT WHITE (1950 4625);
DISPLAY INVISIBLE (1950 4625);
FORCEPROP 2 LAST ROOM PROC_RSTS_PGOODS
J 0
(1925 4225);
DISPLAY 1.617021 (1925 4225);
PAINT WHITE (1925 4225);
DISPLAY INVISIBLE (1925 4225);
FORCEADD PVCCIO_CPU1..1
(1800 2425);
FORCEPROP 3 LASTPIN (1800 2375) SIG_NAME PVCCIO_CPU1\g
J 0
(1810 2385);
DISPLAY 0.659574 (1810 2385);
PAINT MONO (1810 2385);
DISPLAY INVISIBLE (1810 2385);
FORCEPROP 1 LAST VOLTAGE 1.1V
J 0
(1755 2382);
DISPLAY 0.340426 (1755 2382);
PAINT SKYBLUE (1755 2382);
DISPLAY INVISIBLE (1755 2382);
FORCEPROP 2 LAST CDS_LIB mstr_symbols
J 0
(1800 2425);
PAINT ORANGE (1800 2425);
DISPLAY INVISIBLE (1800 2425);
FORCEPROP 1 LAST BODY_TYPE PLUMBING
J 0
(1755 2382);
DISPLAY 0.340426 (1755 2382);
PAINT GREEN (1755 2382);
DISPLAY INVISIBLE (1755 2382);
FORCEPROP 1 LAST PATH I24
J 0
(1850 2450);
DISPLAY 0.872340 (1850 2450);
PAINT AQUA (1850 2450);
DISPLAY INVISIBLE (1850 2450);
FORCEPROP 1 LAST HDL_POWER PVCCIO_CPU1
J 1
(1800 2475);
DISPLAY 0.872340 (1800 2475);
PAINT GREEN (1800 2475);
DISPLAY INVISIBLE (1800 2475);
FORCEADD RES..2
(1900 2150);
FORCEPROP 1 LAST LOCATION R3D20
J 0
(1945 2275);
DISPLAY 0.617021 (1945 2275);
PAINT AQUA (1945 2275);
FORCEPROP 1 LAST PART_NUMBER G21796-047
J 0
(1940 2025);
DISPLAY 0.617021 (1940 2025);
PAINT BLUE (1940 2025);
FORCEPROP 1 LAST VALUE 49.9
J 0
(1945 2225);
DISPLAY 0.617021 (1945 2225);
PAINT SKYBLUE (1945 2225);
FORCEPROP 1 LAST TOLERANCE 1%
J 0
(1945 2175);
DISPLAY 0.617021 (1945 2175);
PAINT SKYBLUE (1945 2175);
FORCEPROP 1 LAST PACK_TYPE 0402
J 0
(1940 1975);
DISPLAY 0.617021 (1940 1975);
PAINT SKYBLUE (1940 1975);
FORCEPROP 1 LAST MATERIAL CHIP
J 0
(1940 2075);
DISPLAY 0.617021 (1940 2075);
PAINT SKYBLUE (1940 2075);
FORCEPROP 1 LAST WATTAGE 1/16W
J 0
(1940 2125);
DISPLAY 0.617021 (1940 2125);
PAINT SKYBLUE (1940 2125);
FORCEPROP 1 LASTPIN (1900 2050) $PN 2
J 0
(1905 2060);
DISPLAY 0.617021 (1905 2060);
PAINT WHITE (1905 2060);
FORCEPROP 1 LASTPIN (1900 2250) $PN 1
J 0
(1905 2212);
DISPLAY 0.617021 (1905 2212);
PAINT WHITE (1905 2212);
FORCEPROP 2 LAST BOM_COST PROC_SIDEBAND
J 0
(1900 2150);
DISPLAY 1.617021 (1900 2150);
PAINT WHITE (1900 2150);
DISPLAY INVISIBLE (1900 2150);
FORCEPROP 2 LAST CDS_LIB mstr_discrete
J 0
(1900 2150);
DISPLAY 1.617021 (1900 2150);
PAINT ORANGE (1900 2150);
DISPLAY INVISIBLE (1900 2150);
FORCEPROP 2 LAST SEC_TYPE 0402
J 0
(1950 2375);
DISPLAY 1.617021 (1950 2375);
PAINT MONO (1950 2375);
DISPLAY INVISIBLE (1950 2375);
FORCEPROP 2 LAST SEC 1
J 0
(1950 2375);
DISPLAY 1.510638 (1950 2375);
PAINT MONO (1950 2375);
DISPLAY INVISIBLE (1950 2375);
FORCEPROP 2 LAST CDS_LOCATION R3D20
J 0
(1945 2275);
DISPLAY 0.617021 (1945 2275);
PAINT AQUA (1945 2275);
DISPLAY INVISIBLE (1945 2275);
FORCEPROP 1 LAST PATH I25
J 0
(1950 2325);
DISPLAY 0.978723 (1950 2325);
PAINT WHITE (1950 2325);
DISPLAY INVISIBLE (1950 2325);
FORCEPROP 2 LAST ROOM PROC_RSTS_PGOODS
J 0
(1925 1925);
DISPLAY 1.617021 (1925 1925);
PAINT WHITE (1925 1925);
DISPLAY INVISIBLE (1925 1925);
FORCEADD RES..2
R 2
(1700 2150);
FORCEPROP 1 LAST LOCATION R3D15
J 2
(1655 2275);
DISPLAY 0.617021 (1655 2275);
PAINT AQUA (1655 2275);
FORCEPROP 1 LAST PART_NUMBER G21796-047
J 2
(1660 2025);
DISPLAY 0.617021 (1660 2025);
PAINT BLUE (1660 2025);
FORCEPROP 1 LAST VALUE 49.9
J 2
(1655 2225);
DISPLAY 0.617021 (1655 2225);
PAINT SKYBLUE (1655 2225);
FORCEPROP 1 LAST TOLERANCE 1%
J 2
(1655 2175);
DISPLAY 0.617021 (1655 2175);
PAINT SKYBLUE (1655 2175);
FORCEPROP 1 LAST PACK_TYPE 0402
J 2
(1660 1975);
DISPLAY 0.617021 (1660 1975);
PAINT SKYBLUE (1660 1975);
FORCEPROP 1 LAST MATERIAL CHIP
J 2
(1660 2075);
DISPLAY 0.617021 (1660 2075);
PAINT SKYBLUE (1660 2075);
FORCEPROP 1 LAST WATTAGE 1/16W
J 2
(1660 2125);
DISPLAY 0.617021 (1660 2125);
PAINT SKYBLUE (1660 2125);
FORCEPROP 1 LASTPIN (1700 2050) $PN 2
J 2
(1695 2060);
DISPLAY 0.617021 (1695 2060);
PAINT WHITE (1695 2060);
FORCEPROP 1 LASTPIN (1700 2250) $PN 1
J 2
(1695 2212);
DISPLAY 0.617021 (1695 2212);
PAINT WHITE (1695 2212);
FORCEPROP 2 LAST BOM_COST PROC_SIDEBAND
J 2
(1700 2150);
DISPLAY 1.617021 (1700 2150);
PAINT WHITE (1700 2150);
DISPLAY INVISIBLE (1700 2150);
FORCEPROP 2 LAST CDS_LIB mstr_discrete
J 2
(1700 2150);
DISPLAY 1.617021 (1700 2150);
PAINT ORANGE (1700 2150);
DISPLAY INVISIBLE (1700 2150);
FORCEPROP 2 LAST SEC_TYPE 0402
J 2
(1650 2375);
DISPLAY 1.617021 (1650 2375);
PAINT MONO (1650 2375);
DISPLAY INVISIBLE (1650 2375);
FORCEPROP 2 LAST SEC 1
J 2
(1650 2375);
DISPLAY 1.510638 (1650 2375);
PAINT MONO (1650 2375);
DISPLAY INVISIBLE (1650 2375);
FORCEPROP 2 LAST CDS_LOCATION R3D15
J 2
(1655 2275);
DISPLAY 0.617021 (1655 2275);
PAINT AQUA (1655 2275);
DISPLAY INVISIBLE (1655 2275);
FORCEPROP 1 LAST PATH I26
J 2
(1650 2325);
DISPLAY 0.978723 (1650 2325);
PAINT WHITE (1650 2325);
DISPLAY INVISIBLE (1650 2325);
FORCEPROP 2 LAST ROOM PROC_RSTS_PGOODS
J 2
(1675 1925);
DISPLAY 1.617021 (1675 1925);
PAINT WHITE (1675 1925);
DISPLAY INVISIBLE (1675 1925);
FORCEADD PVDDQ_KLM..1
(975 2400);
FORCEPROP 3 LASTPIN (975 2350) SIG_NAME PVDDQ_KLM\g
J 0
(985 2360);
DISPLAY 0.659574 (985 2360);
PAINT MONO (985 2360);
DISPLAY INVISIBLE (985 2360);
FORCEPROP 1 LAST VOLTAGE 1.2V
J 0
(930 2357);
DISPLAY 0.340426 (930 2357);
PAINT SKYBLUE (930 2357);
DISPLAY INVISIBLE (930 2357);
FORCEPROP 2 LAST CDS_LIB mstr_symbols
J 0
(975 2400);
PAINT ORANGE (975 2400);
DISPLAY INVISIBLE (975 2400);
FORCEPROP 1 LAST BODY_TYPE PLUMBING
J 0
(930 2357);
DISPLAY 0.340426 (930 2357);
PAINT GREEN (930 2357);
DISPLAY INVISIBLE (930 2357);
FORCEPROP 1 LAST PATH I27
J 0
(1025 2425);
DISPLAY 0.872340 (1025 2425);
PAINT AQUA (1025 2425);
DISPLAY INVISIBLE (1025 2425);
FORCEPROP 1 LAST HDL_POWER PVDDQ_KLM
J 1
(975 2450);
DISPLAY 0.872340 (975 2450);
PAINT GREEN (975 2450);
DISPLAY INVISIBLE (975 2450);
FORCEADD RES..2
(975 2150);
FORCEPROP 1 LAST LOCATION R7M9
J 0
(1020 2275);
DISPLAY 0.617021 (1020 2275);
PAINT AQUA (1020 2275);
FORCEPROP 1 LAST PART_NUMBER G21796-298
J 0
(1015 2025);
DISPLAY 0.617021 (1015 2025);
PAINT BLUE (1015 2025);
FORCEPROP 1 LAST VALUE 64.9
J 0
(1020 2225);
DISPLAY 0.617021 (1020 2225);
PAINT SKYBLUE (1020 2225);
FORCEPROP 1 LAST TOLERANCE 1.0%
J 0
(1020 2175);
DISPLAY 0.617021 (1020 2175);
PAINT SKYBLUE (1020 2175);
FORCEPROP 1 LAST PACK_TYPE 0402
J 0
(1015 1975);
DISPLAY 0.617021 (1015 1975);
PAINT SKYBLUE (1015 1975);
FORCEPROP 1 LAST MATERIAL CHIP
J 0
(1015 2075);
DISPLAY 0.617021 (1015 2075);
PAINT SKYBLUE (1015 2075);
FORCEPROP 1 LAST WATTAGE 1/16W
J 0
(1015 2125);
DISPLAY 0.617021 (1015 2125);
PAINT SKYBLUE (1015 2125);
FORCEPROP 1 LASTPIN (975 2050) $PN 2
J 0
(980 2060);
DISPLAY 0.617021 (980 2060);
PAINT WHITE (980 2060);
FORCEPROP 1 LASTPIN (975 2250) $PN 1
J 0
(980 2212);
DISPLAY 0.617021 (980 2212);
PAINT WHITE (980 2212);
FORCEPROP 2 LAST BOM_COST PROC_SIDEBAND
J 0
(1025 2325);
DISPLAY 1.659574 (1025 2325);
PAINT WHITE (1025 2325);
DISPLAY INVISIBLE (1025 2325);
FORCEPROP 2 LAST CDS_LIB mstr_discrete
J 0
(975 2150);
DISPLAY 1.617021 (975 2150);
PAINT ORANGE (975 2150);
DISPLAY INVISIBLE (975 2150);
FORCEPROP 2 LAST CDS_SEC 1
J 0
(1025 2375);
DISPLAY 2.276596 (1025 2375);
PAINT ORANGE (1025 2375);
DISPLAY INVISIBLE (1025 2375);
FORCEPROP 2 LAST $SEC 1
J 0
(1025 2375);
DISPLAY 1.510638 (1025 2375);
PAINT MONO (1025 2375);
DISPLAY INVISIBLE (1025 2375);
FORCEPROP 2 LAST CDS_LOCATION R7M9
J 0
(1020 2275);
DISPLAY 0.617021 (1020 2275);
PAINT AQUA (1020 2275);
DISPLAY INVISIBLE (1020 2275);
FORCEPROP 1 LAST PATH I28
J 0
(1025 2325);
DISPLAY 0.978723 (1025 2325);
PAINT WHITE (1025 2325);
DISPLAY INVISIBLE (1025 2325);
FORCEPROP 2 LAST ROOM PROC_RSTS_PGOODS
J 0
(1025 2325);
DISPLAY 2.276596 (1025 2325);
PAINT WHITE (1025 2325);
DISPLAY INVISIBLE (1025 2325);
FORCEADD PVDDQ_GHJ..1
(575 2400);
FORCEPROP 3 LASTPIN (575 2350) SIG_NAME PVDDQ_GHJ\g
J 0
(585 2360);
DISPLAY 0.659574 (585 2360);
PAINT MONO (585 2360);
DISPLAY INVISIBLE (585 2360);
FORCEPROP 1 LAST VOLTAGE 1.2V
J 0
(530 2357);
DISPLAY 0.340426 (530 2357);
PAINT SKYBLUE (530 2357);
DISPLAY INVISIBLE (530 2357);
FORCEPROP 2 LAST CDS_LIB mstr_symbols
J 0
(575 2400);
PAINT ORANGE (575 2400);
DISPLAY INVISIBLE (575 2400);
FORCEPROP 1 LAST BODY_TYPE PLUMBING
J 0
(530 2357);
DISPLAY 0.340426 (530 2357);
PAINT GREEN (530 2357);
DISPLAY INVISIBLE (530 2357);
FORCEPROP 1 LAST PATH I29
J 0
(625 2425);
DISPLAY 0.872340 (625 2425);
PAINT AQUA (625 2425);
DISPLAY INVISIBLE (625 2425);
FORCEPROP 1 LAST HDL_POWER PVDDQ_GHJ
J 1
(575 2450);
DISPLAY 0.872340 (575 2450);
PAINT GREEN (575 2450);
DISPLAY INVISIBLE (575 2450);
FORCEADD RES..2
R 2
(1700 4450);
FORCEPROP 1 LAST LOCATION R6D8
J 2
(1655 4575);
DISPLAY 0.617021 (1655 4575);
PAINT AQUA (1655 4575);
FORCEPROP 1 LAST PART_NUMBER G21796-047
J 2
(1660 4325);
DISPLAY 0.617021 (1660 4325);
PAINT BLUE (1660 4325);
FORCEPROP 1 LAST VALUE 49.9
J 2
(1655 4525);
DISPLAY 0.617021 (1655 4525);
PAINT SKYBLUE (1655 4525);
FORCEPROP 1 LAST TOLERANCE 1%
J 2
(1655 4475);
DISPLAY 0.617021 (1655 4475);
PAINT SKYBLUE (1655 4475);
FORCEPROP 1 LAST PACK_TYPE 0402
J 2
(1660 4275);
DISPLAY 0.617021 (1660 4275);
PAINT SKYBLUE (1660 4275);
FORCEPROP 1 LAST MATERIAL CHIP
J 2
(1660 4375);
DISPLAY 0.617021 (1660 4375);
PAINT SKYBLUE (1660 4375);
FORCEPROP 1 LAST WATTAGE 1/16W
J 2
(1660 4425);
DISPLAY 0.617021 (1660 4425);
PAINT SKYBLUE (1660 4425);
FORCEPROP 1 LASTPIN (1700 4350) $PN 2
J 2
(1695 4360);
DISPLAY 0.617021 (1695 4360);
PAINT WHITE (1695 4360);
FORCEPROP 1 LASTPIN (1700 4550) $PN 1
J 2
(1695 4512);
DISPLAY 0.617021 (1695 4512);
PAINT WHITE (1695 4512);
FORCEPROP 2 LAST BOM_COST PROC_SIDEBAND
J 2
(1700 4450);
DISPLAY 1.617021 (1700 4450);
PAINT WHITE (1700 4450);
DISPLAY INVISIBLE (1700 4450);
FORCEPROP 2 LAST CDS_LIB mstr_discrete
J 2
(1700 4450);
DISPLAY 1.617021 (1700 4450);
PAINT ORANGE (1700 4450);
DISPLAY INVISIBLE (1700 4450);
FORCEPROP 2 LAST SEC_TYPE 0402
J 2
(1650 4675);
DISPLAY 1.617021 (1650 4675);
PAINT MONO (1650 4675);
DISPLAY INVISIBLE (1650 4675);
FORCEPROP 2 LAST SEC 1
J 2
(1650 4675);
DISPLAY 1.510638 (1650 4675);
PAINT MONO (1650 4675);
DISPLAY INVISIBLE (1650 4675);
FORCEPROP 2 LAST CDS_LOCATION R6D8
J 2
(1655 4575);
DISPLAY 0.617021 (1655 4575);
PAINT AQUA (1655 4575);
DISPLAY INVISIBLE (1655 4575);
FORCEPROP 1 LAST PATH I3
J 2
(1650 4625);
DISPLAY 0.978723 (1650 4625);
PAINT WHITE (1650 4625);
DISPLAY INVISIBLE (1650 4625);
FORCEPROP 2 LAST ROOM PROC_RSTS_PGOODS
J 2
(1675 4225);
DISPLAY 1.617021 (1675 4225);
PAINT WHITE (1675 4225);
DISPLAY INVISIBLE (1675 4225);
FORCEADD RES..2
(575 2150);
FORCEPROP 1 LAST LOCATION R3D21
J 0
(620 2275);
DISPLAY 0.617021 (620 2275);
PAINT AQUA (620 2275);
FORCEPROP 1 LAST PART_NUMBER G21796-298
J 0
(615 2025);
DISPLAY 0.617021 (615 2025);
PAINT BLUE (615 2025);
FORCEPROP 1 LAST VALUE 64.9
J 0
(620 2225);
DISPLAY 0.617021 (620 2225);
PAINT SKYBLUE (620 2225);
FORCEPROP 1 LAST TOLERANCE 1.0%
J 0
(620 2175);
DISPLAY 0.617021 (620 2175);
PAINT SKYBLUE (620 2175);
FORCEPROP 1 LAST PACK_TYPE 0402
J 0
(615 1975);
DISPLAY 0.617021 (615 1975);
PAINT SKYBLUE (615 1975);
FORCEPROP 1 LAST MATERIAL CHIP
J 0
(615 2075);
DISPLAY 0.617021 (615 2075);
PAINT SKYBLUE (615 2075);
FORCEPROP 1 LAST WATTAGE 1/16W
J 0
(615 2125);
DISPLAY 0.617021 (615 2125);
PAINT SKYBLUE (615 2125);
FORCEPROP 1 LASTPIN (575 2050) $PN 2
J 0
(580 2060);
DISPLAY 0.617021 (580 2060);
PAINT WHITE (580 2060);
FORCEPROP 1 LASTPIN (575 2250) $PN 1
J 0
(580 2212);
DISPLAY 0.617021 (580 2212);
PAINT WHITE (580 2212);
FORCEPROP 2 LAST BOM_COST PROC_SIDEBAND
J 0
(625 2325);
DISPLAY 1.659574 (625 2325);
PAINT WHITE (625 2325);
DISPLAY INVISIBLE (625 2325);
FORCEPROP 2 LAST CDS_LIB mstr_discrete
J 0
(575 2150);
DISPLAY 1.617021 (575 2150);
PAINT ORANGE (575 2150);
DISPLAY INVISIBLE (575 2150);
FORCEPROP 2 LAST CDS_SEC 1
J 0
(625 2375);
DISPLAY 2.276596 (625 2375);
PAINT ORANGE (625 2375);
DISPLAY INVISIBLE (625 2375);
FORCEPROP 2 LAST $SEC 1
J 0
(625 2375);
DISPLAY 1.510638 (625 2375);
PAINT MONO (625 2375);
DISPLAY INVISIBLE (625 2375);
FORCEPROP 2 LAST CDS_LOCATION R3D21
J 0
(620 2275);
DISPLAY 0.617021 (620 2275);
PAINT AQUA (620 2275);
DISPLAY INVISIBLE (620 2275);
FORCEPROP 1 LAST PATH I30
J 0
(625 2325);
DISPLAY 0.978723 (625 2325);
PAINT WHITE (625 2325);
DISPLAY INVISIBLE (625 2325);
FORCEPROP 2 LAST ROOM PROC_RSTS_PGOODS
J 0
(625 2325);
DISPLAY 2.276596 (625 2325);
PAINT WHITE (625 2325);
DISPLAY INVISIBLE (625 2325);
FORCEADD RES..2
(-2100 4650);
FORCEPROP 1 LAST LOCATION R3P36
J 0
(-2055 4775);
DISPLAY 0.617021 (-2055 4775);
PAINT AQUA (-2055 4775);
FORCEPROP 1 LAST PART_NUMBER G21796-026
J 0
(-2060 4525);
DISPLAY 0.617021 (-2060 4525);
PAINT BLUE (-2060 4525);
FORCEPROP 1 LAST VALUE 1.00K
J 0
(-2055 4725);
DISPLAY 0.617021 (-2055 4725);
PAINT SKYBLUE (-2055 4725);
FORCEPROP 1 LAST TOLERANCE 1%
J 0
(-2055 4675);
DISPLAY 0.617021 (-2055 4675);
PAINT SKYBLUE (-2055 4675);
FORCEPROP 1 LAST PACK_TYPE 0402
J 0
(-2060 4475);
DISPLAY 0.617021 (-2060 4475);
PAINT SKYBLUE (-2060 4475);
FORCEPROP 1 LAST MATERIAL CHIP
J 0
(-2060 4575);
DISPLAY 0.617021 (-2060 4575);
PAINT SKYBLUE (-2060 4575);
FORCEPROP 1 LAST WATTAGE 1/16W
J 0
(-2060 4625);
DISPLAY 0.617021 (-2060 4625);
PAINT SKYBLUE (-2060 4625);
FORCEPROP 1 LASTPIN (-2100 4550) $PN 2
J 0
(-2095 4560);
DISPLAY 0.617021 (-2095 4560);
PAINT WHITE (-2095 4560);
FORCEPROP 1 LASTPIN (-2100 4750) $PN 1
J 0
(-2095 4712);
DISPLAY 0.617021 (-2095 4712);
PAINT WHITE (-2095 4712);
FORCEPROP 2 LAST BOM_COST PROC_SIDEBAND
J 0
(-2100 4650);
DISPLAY 1.617021 (-2100 4650);
PAINT WHITE (-2100 4650);
DISPLAY INVISIBLE (-2100 4650);
FORCEPROP 2 LAST CDS_LIB mstr_discrete
J 0
(-2100 4650);
DISPLAY 1.617021 (-2100 4650);
PAINT ORANGE (-2100 4650);
DISPLAY INVISIBLE (-2100 4650);
FORCEPROP 2 LAST CDS_SEC 1
J 0
(-2050 4875);
DISPLAY 2.276596 (-2050 4875);
PAINT ORANGE (-2050 4875);
DISPLAY INVISIBLE (-2050 4875);
FORCEPROP 2 LAST $SEC 1
J 0
(-2050 4875);
DISPLAY 1.510638 (-2050 4875);
PAINT MONO (-2050 4875);
DISPLAY INVISIBLE (-2050 4875);
FORCEPROP 2 LAST CDS_LOCATION R3P36
J 0
(-2055 4775);
DISPLAY 0.617021 (-2055 4775);
PAINT AQUA (-2055 4775);
DISPLAY INVISIBLE (-2055 4775);
FORCEPROP 1 LAST PATH I36
J 0
(-2050 4825);
DISPLAY 0.978723 (-2050 4825);
PAINT WHITE (-2050 4825);
DISPLAY INVISIBLE (-2050 4825);
FORCEPROP 2 LAST ROOM PROC_RSTS_PGOODS
J 0
(-2075 4425);
DISPLAY 1.617021 (-2075 4425);
PAINT WHITE (-2075 4425);
DISPLAY INVISIBLE (-2075 4425);
FORCEADD PVDDQ_DEF..1
(975 4700);
FORCEPROP 3 LASTPIN (975 4650) SIG_NAME PVDDQ_DEF\g
J 0
(985 4660);
DISPLAY 0.659574 (985 4660);
PAINT MONO (985 4660);
DISPLAY INVISIBLE (985 4660);
FORCEPROP 1 LAST VOLTAGE 1.2V
J 0
(930 4657);
DISPLAY 0.340426 (930 4657);
PAINT SKYBLUE (930 4657);
DISPLAY INVISIBLE (930 4657);
FORCEPROP 2 LAST CDS_LIB mstr_symbols
J 0
(975 4700);
PAINT ORANGE (975 4700);
DISPLAY INVISIBLE (975 4700);
FORCEPROP 1 LAST BODY_TYPE PLUMBING
J 0
(930 4657);
DISPLAY 0.340426 (930 4657);
PAINT GREEN (930 4657);
DISPLAY INVISIBLE (930 4657);
FORCEPROP 1 LAST PATH I4
J 0
(1025 4725);
DISPLAY 0.872340 (1025 4725);
PAINT AQUA (1025 4725);
DISPLAY INVISIBLE (1025 4725);
FORCEPROP 1 LAST HDL_POWER PVDDQ_DEF
J 1
(975 4750);
DISPLAY 0.872340 (975 4750);
PAINT GREEN (975 4750);
DISPLAY INVISIBLE (975 4750);
FORCEADD GND..1
(-325 3550);
FORCEPROP 3 LASTPIN (-325 3600) SIG_NAME GND\g
J 0
(-315 3610);
DISPLAY 0.659574 (-315 3610);
PAINT MONO (-315 3610);
DISPLAY INVISIBLE (-315 3610);
FORCEPROP 1 LAST VOLTAGE 0.0V
J 0
(-370 3507);
DISPLAY 0.340426 (-370 3507);
PAINT SKYBLUE (-370 3507);
DISPLAY INVISIBLE (-370 3507);
FORCEPROP 1 LAST SIZE 1B
J 0
(-250 3500);
DISPLAY 1.893617 (-250 3500);
PAINT GREEN (-250 3500);
DISPLAY INVISIBLE (-250 3500);
FORCEPROP 2 LAST CDS_LIB mstr_symbols
J 0
(-325 3550);
PAINT ORANGE (-325 3550);
DISPLAY INVISIBLE (-325 3550);
FORCEPROP 1 LAST BODY_TYPE PLUMBING
J 0
(-370 3507);
DISPLAY 0.340426 (-370 3507);
PAINT GREEN (-370 3507);
DISPLAY INVISIBLE (-370 3507);
FORCEPROP 1 LAST PATH I41
J 0
(-250 3550);
DISPLAY 0.872340 (-250 3550);
PAINT AQUA (-250 3550);
DISPLAY INVISIBLE (-250 3550);
FORCEPROP 1 LAST HDL_POWER GND
J 0
(-325 3700);
DISPLAY 1.595745 (-325 3700);
PAINT GREEN (-325 3700);
DISPLAY INVISIBLE (-325 3700);
FORCEADD GTL2014..1
(-875 4100);
FORCEPROP 1 LAST LOCATION U3P1
J 0
(-1275 4650);
DISPLAY 0.617021 (-1275 4650);
PAINT AQUA (-1275 4650);
FORCEPROP 1 LAST PART_NUMBER D66151-001
J 0
(-975 3600);
DISPLAY 0.617021 (-975 3600);
PAINT BLUE (-975 3600);
FORCEPROP 1 LAST MATERIAL IC
J 0
(-1275 4600);
DISPLAY 0.617021 (-1275 4600);
PAINT SKYBLUE (-1275 4600);
FORCEPROP 2 LASTPIN (-1325 4350) $PN 4
J 2
(-1335 4360);
DISPLAY 0.617021 (-1335 4360);
PAINT WHITE (-1335 4360);
FORCEPROP 2 LASTPIN (-1325 4400) $PN 14
J 2
(-1335 4410);
DISPLAY 0.617021 (-1335 4410);
PAINT WHITE (-1335 4410);
FORCEPROP 2 LASTPIN (-425 3800) $PN 11
J 0
(-415 3810);
DISPLAY 0.617021 (-415 3810);
PAINT WHITE (-415 3810);
FORCEPROP 2 LASTPIN (-425 3750) $PN 8
J 0
(-415 3760);
DISPLAY 0.617021 (-415 3760);
PAINT WHITE (-415 3760);
FORCEPROP 2 LASTPIN (-425 3700) $PN 7
J 0
(-415 3710);
DISPLAY 0.617021 (-415 3710);
PAINT WHITE (-415 3710);
FORCEPROP 2 LASTPIN (-1325 4250) $PN 1
J 2
(-1335 4260);
DISPLAY 0.617021 (-1335 4260);
PAINT WHITE (-1335 4260);
FORCEPROP 2 LASTPIN (-425 4100) $PN 6
J 0
(-415 4110);
DISPLAY 0.617021 (-415 4110);
PAINT WHITE (-415 4110);
FORCEPROP 2 LASTPIN (-425 4050) $PN 5
J 0
(-415 4060);
DISPLAY 0.617021 (-415 4060);
PAINT WHITE (-415 4060);
FORCEPROP 2 LASTPIN (-425 4000) $PN 3
J 0
(-415 4010);
DISPLAY 0.617021 (-415 4010);
PAINT WHITE (-415 4010);
FORCEPROP 2 LASTPIN (-425 3950) $PN 2
J 0
(-415 3960);
DISPLAY 0.617021 (-415 3960);
PAINT WHITE (-415 3960);
FORCEPROP 2 LASTPIN (-1325 4100) $PN 9
J 2
(-1335 4110);
DISPLAY 0.617021 (-1335 4110);
PAINT WHITE (-1335 4110);
FORCEPROP 2 LASTPIN (-1325 4050) $PN 10
J 2
(-1335 4060);
DISPLAY 0.617021 (-1335 4060);
PAINT WHITE (-1335 4060);
FORCEPROP 2 LASTPIN (-1325 4000) $PN 12
J 2
(-1335 4010);
DISPLAY 0.617021 (-1335 4010);
PAINT WHITE (-1335 4010);
FORCEPROP 2 LASTPIN (-1325 3950) $PN 13
J 2
(-1335 3960);
DISPLAY 0.617021 (-1335 3960);
PAINT WHITE (-1335 3960);
FORCEPROP 1 LAST PACK_TYPE SM
J 0
(-1275 4700);
DISPLAY 1.617021 (-1275 4700);
PAINT SKYBLUE (-1275 4700);
DISPLAY INVISIBLE (-1275 4700);
FORCEPROP 2 LAST BOM_COST PROC_SIDEBAND
J 0
(-875 4100);
DISPLAY 1.617021 (-875 4100);
PAINT WHITE (-875 4100);
DISPLAY INVISIBLE (-875 4100);
FORCEPROP 2 LAST CDS_LIB mstr_digital
J 0
(-875 4100);
DISPLAY 1.617021 (-875 4100);
PAINT MONO (-875 4100);
DISPLAY INVISIBLE (-875 4100);
FORCEPROP 2 LAST CDS_SEC 1
J 2
(-1275 4700);
DISPLAY 2.276596 (-1275 4700);
PAINT ORANGE (-1275 4700);
DISPLAY INVISIBLE (-1275 4700);
FORCEPROP 2 LAST $SEC 1
J 2
(-1275 4700);
DISPLAY 1.510638 (-1275 4700);
PAINT MONO (-1275 4700);
DISPLAY INVISIBLE (-1275 4700);
FORCEPROP 2 LAST CDS_LOCATION U3P1
J 0
(-1275 4650);
DISPLAY 0.617021 (-1275 4650);
PAINT AQUA (-1275 4650);
DISPLAY INVISIBLE (-1275 4650);
FORCEPROP 1 LAST PATH I42
J 0
(-875 4600);
PAINT GREEN (-875 4600);
DISPLAY INVISIBLE (-875 4600);
FORCEPROP 2 LAST ROOM PROC_RSTS_PGOODS
J 2
(-1275 4700);
DISPLAY 2.276596 (-1275 4700);
PAINT WHITE (-1275 4700);
DISPLAY INVISIBLE (-1275 4700);
FORCEADD GND..1
(-325 1250);
FORCEPROP 3 LASTPIN (-325 1300) SIG_NAME GND\g
J 0
(-315 1310);
DISPLAY 0.659574 (-315 1310);
PAINT MONO (-315 1310);
DISPLAY INVISIBLE (-315 1310);
FORCEPROP 1 LAST VOLTAGE 0.0V
J 0
(-370 1207);
DISPLAY 0.340426 (-370 1207);
PAINT SKYBLUE (-370 1207);
DISPLAY INVISIBLE (-370 1207);
FORCEPROP 2 LAST CDS_LIB mstr_symbols
J 0
(-325 1250);
PAINT ORANGE (-325 1250);
DISPLAY INVISIBLE (-325 1250);
FORCEPROP 1 LAST SIZE 1B
J 0
(-250 1200);
DISPLAY 1.893617 (-250 1200);
PAINT GREEN (-250 1200);
DISPLAY INVISIBLE (-250 1200);
FORCEPROP 1 LAST BODY_TYPE PLUMBING
J 0
(-370 1207);
DISPLAY 0.340426 (-370 1207);
PAINT GREEN (-370 1207);
DISPLAY INVISIBLE (-370 1207);
FORCEPROP 1 LAST PATH I45
J 0
(-250 1250);
DISPLAY 0.872340 (-250 1250);
PAINT AQUA (-250 1250);
DISPLAY INVISIBLE (-250 1250);
FORCEPROP 1 LAST HDL_POWER GND
J 0
(-325 1400);
DISPLAY 1.595745 (-325 1400);
PAINT GREEN (-325 1400);
DISPLAY INVISIBLE (-325 1400);
FORCEADD GTL2014..1
(-875 1800);
FORCEPROP 1 LAST LOCATION U4C2
J 0
(-1275 2350);
DISPLAY 0.617021 (-1275 2350);
PAINT AQUA (-1275 2350);
FORCEPROP 1 LAST PART_NUMBER D66151-001
J 0
(-975 1300);
DISPLAY 0.617021 (-975 1300);
PAINT BLUE (-975 1300);
FORCEPROP 1 LAST MATERIAL IC
J 0
(-1275 2300);
DISPLAY 0.617021 (-1275 2300);
PAINT SKYBLUE (-1275 2300);
FORCEPROP 2 LASTPIN (-1325 2050) $PN 4
J 2
(-1335 2060);
DISPLAY 0.617021 (-1335 2060);
PAINT WHITE (-1335 2060);
FORCEPROP 2 LASTPIN (-1325 2100) $PN 14
J 2
(-1335 2110);
DISPLAY 0.617021 (-1335 2110);
PAINT WHITE (-1335 2110);
FORCEPROP 2 LASTPIN (-425 1500) $PN 11
J 0
(-415 1510);
DISPLAY 0.617021 (-415 1510);
PAINT WHITE (-415 1510);
FORCEPROP 2 LASTPIN (-425 1450) $PN 8
J 0
(-415 1460);
DISPLAY 0.617021 (-415 1460);
PAINT WHITE (-415 1460);
FORCEPROP 2 LASTPIN (-425 1400) $PN 7
J 0
(-415 1410);
DISPLAY 0.617021 (-415 1410);
PAINT WHITE (-415 1410);
FORCEPROP 2 LASTPIN (-1325 1950) $PN 1
J 2
(-1335 1960);
DISPLAY 0.617021 (-1335 1960);
PAINT WHITE (-1335 1960);
FORCEPROP 2 LASTPIN (-425 1800) $PN 6
J 0
(-415 1810);
DISPLAY 0.617021 (-415 1810);
PAINT WHITE (-415 1810);
FORCEPROP 2 LASTPIN (-425 1750) $PN 5
J 0
(-415 1760);
DISPLAY 0.617021 (-415 1760);
PAINT WHITE (-415 1760);
FORCEPROP 2 LASTPIN (-425 1700) $PN 3
J 0
(-415 1710);
DISPLAY 0.617021 (-415 1710);
PAINT WHITE (-415 1710);
FORCEPROP 2 LASTPIN (-425 1650) $PN 2
J 0
(-415 1660);
DISPLAY 0.617021 (-415 1660);
PAINT WHITE (-415 1660);
FORCEPROP 2 LASTPIN (-1325 1800) $PN 9
J 2
(-1335 1810);
DISPLAY 0.617021 (-1335 1810);
PAINT WHITE (-1335 1810);
FORCEPROP 2 LASTPIN (-1325 1750) $PN 10
J 2
(-1335 1760);
DISPLAY 0.617021 (-1335 1760);
PAINT WHITE (-1335 1760);
FORCEPROP 2 LASTPIN (-1325 1700) $PN 12
J 2
(-1335 1710);
DISPLAY 0.617021 (-1335 1710);
PAINT WHITE (-1335 1710);
FORCEPROP 2 LASTPIN (-1325 1650) $PN 13
J 2
(-1335 1660);
DISPLAY 0.617021 (-1335 1660);
PAINT WHITE (-1335 1660);
FORCEPROP 1 LAST PACK_TYPE SM
J 0
(-1275 2400);
DISPLAY 1.617021 (-1275 2400);
PAINT SKYBLUE (-1275 2400);
DISPLAY INVISIBLE (-1275 2400);
FORCEPROP 2 LAST CDS_LIB mstr_digital
J 0
(-875 1800);
DISPLAY 1.617021 (-875 1800);
PAINT MONO (-875 1800);
DISPLAY INVISIBLE (-875 1800);
FORCEPROP 2 LAST BOM_COST PROC_SIDEBAND
J 0
(-875 1800);
DISPLAY 1.617021 (-875 1800);
PAINT WHITE (-875 1800);
DISPLAY INVISIBLE (-875 1800);
FORCEPROP 2 LAST CDS_SEC 1
J 2
(-1275 2400);
DISPLAY 2.276596 (-1275 2400);
PAINT ORANGE (-1275 2400);
DISPLAY INVISIBLE (-1275 2400);
FORCEPROP 2 LAST $SEC 1
J 2
(-1275 2400);
DISPLAY 1.510638 (-1275 2400);
PAINT MONO (-1275 2400);
DISPLAY INVISIBLE (-1275 2400);
FORCEPROP 2 LAST CDS_LOCATION U4C2
J 0
(-1275 2350);
DISPLAY 0.617021 (-1275 2350);
PAINT AQUA (-1275 2350);
DISPLAY INVISIBLE (-1275 2350);
FORCEPROP 1 LAST PATH I46
J 0
(-875 2300);
PAINT GREEN (-875 2300);
DISPLAY INVISIBLE (-875 2300);
FORCEPROP 2 LAST ROOM PROC_RSTS_PGOODS
J 2
(-1275 2400);
DISPLAY 2.276596 (-1275 2400);
PAINT WHITE (-1275 2400);
DISPLAY INVISIBLE (-1275 2400);
FORCEADD RES..2
(975 4450);
FORCEPROP 1 LAST LOCATION R3P29
J 0
(1020 4575);
DISPLAY 0.617021 (1020 4575);
PAINT AQUA (1020 4575);
FORCEPROP 1 LAST PART_NUMBER G21796-298
J 0
(1015 4325);
DISPLAY 0.617021 (1015 4325);
PAINT BLUE (1015 4325);
FORCEPROP 1 LAST VALUE 64.9
J 0
(1020 4525);
DISPLAY 0.617021 (1020 4525);
PAINT SKYBLUE (1020 4525);
FORCEPROP 1 LAST TOLERANCE 1.0%
J 0
(1020 4475);
DISPLAY 0.617021 (1020 4475);
PAINT SKYBLUE (1020 4475);
FORCEPROP 1 LAST PACK_TYPE 0402
J 0
(1015 4275);
DISPLAY 0.617021 (1015 4275);
PAINT SKYBLUE (1015 4275);
FORCEPROP 1 LAST MATERIAL CHIP
J 0
(1015 4375);
DISPLAY 0.617021 (1015 4375);
PAINT SKYBLUE (1015 4375);
FORCEPROP 1 LAST WATTAGE 1/16W
J 0
(1015 4425);
DISPLAY 0.617021 (1015 4425);
PAINT SKYBLUE (1015 4425);
FORCEPROP 1 LASTPIN (975 4350) $PN 2
J 0
(980 4360);
DISPLAY 0.617021 (980 4360);
PAINT WHITE (980 4360);
FORCEPROP 1 LASTPIN (975 4550) $PN 1
J 0
(980 4512);
DISPLAY 0.617021 (980 4512);
PAINT WHITE (980 4512);
FORCEPROP 2 LAST BOM_COST PROC_SIDEBAND
J 0
(1025 4625);
DISPLAY 1.659574 (1025 4625);
PAINT WHITE (1025 4625);
DISPLAY INVISIBLE (1025 4625);
FORCEPROP 2 LAST CDS_LIB mstr_discrete
J 0
(975 4450);
DISPLAY 1.617021 (975 4450);
PAINT ORANGE (975 4450);
DISPLAY INVISIBLE (975 4450);
FORCEPROP 2 LAST CDS_SEC 1
J 0
(1025 4675);
DISPLAY 2.276596 (1025 4675);
PAINT ORANGE (1025 4675);
DISPLAY INVISIBLE (1025 4675);
FORCEPROP 2 LAST $SEC 1
J 0
(1025 4675);
DISPLAY 1.510638 (1025 4675);
PAINT MONO (1025 4675);
DISPLAY INVISIBLE (1025 4675);
FORCEPROP 2 LAST CDS_LOCATION R3P29
J 0
(1020 4575);
DISPLAY 0.617021 (1020 4575);
PAINT AQUA (1020 4575);
DISPLAY INVISIBLE (1020 4575);
FORCEPROP 1 LAST PATH I5
J 0
(1025 4625);
DISPLAY 0.978723 (1025 4625);
PAINT WHITE (1025 4625);
DISPLAY INVISIBLE (1025 4625);
FORCEPROP 2 LAST ROOM PROC_RSTS_PGOODS
J 0
(1025 4625);
DISPLAY 2.276596 (1025 4625);
PAINT WHITE (1025 4625);
DISPLAY INVISIBLE (1025 4625);
FORCEADD OFFPAGE..1
(-2200 4100);
FORCEPROP 2 LAST $XR0 190 
J 0
(-2452 4100);
DISPLAY 0.638298 (-2452 4100);
PAINT MONO (-2452 4100);
FORCEPROP 2 LAST CDS_LIB mstr_standard
J 0
(-2200 4100);
PAINT ORANGE (-2200 4100);
DISPLAY INVISIBLE (-2200 4100);
FORCEPROP 1 LAST OFFPAGE TRUE
J 0
(-1875 3975);
DISPLAY 1.404255 (-1875 3975);
PAINT GREEN (-1875 3975);
DISPLAY INVISIBLE (-1875 3975);
FORCEPROP 1 LAST COMMENT_BODY TRUE
J 0
(-2075 4000);
DISPLAY 1.404255 (-2075 4000);
PAINT PEACH (-2075 4000);
DISPLAY INVISIBLE (-2075 4000);
FORCEPROP 2 LAST PATH I51
J 0
(-2450 4150);
DISPLAY 1.021277 (-2450 4150);
PAINT ORANGE (-2450 4150);
DISPLAY INVISIBLE (-2450 4150);
FORCEADD OFFPAGE..1
(-2200 4050);
FORCEPROP 2 LAST $XR0 190 
J 0
(-2452 4050);
DISPLAY 0.638298 (-2452 4050);
PAINT MONO (-2452 4050);
FORCEPROP 2 LAST CDS_LIB mstr_standard
J 0
(-2200 4050);
PAINT ORANGE (-2200 4050);
DISPLAY INVISIBLE (-2200 4050);
FORCEPROP 1 LAST OFFPAGE TRUE
J 0
(-1875 3925);
DISPLAY 1.404255 (-1875 3925);
PAINT GREEN (-1875 3925);
DISPLAY INVISIBLE (-1875 3925);
FORCEPROP 1 LAST COMMENT_BODY TRUE
J 0
(-2075 3950);
DISPLAY 1.404255 (-2075 3950);
PAINT PEACH (-2075 3950);
DISPLAY INVISIBLE (-2075 3950);
FORCEPROP 2 LAST PATH I52
J 0
(-2450 4100);
DISPLAY 1.021277 (-2450 4100);
PAINT ORANGE (-2450 4100);
DISPLAY INVISIBLE (-2450 4100);
FORCEADD OFFPAGE..1
(-2200 4000);
FORCEPROP 2 LAST $XR0 190 
J 0
(-2452 4000);
DISPLAY 0.638298 (-2452 4000);
PAINT MONO (-2452 4000);
FORCEPROP 2 LAST $XR1 96 
J 0
(-2542 4000);
DISPLAY 0.638298 (-2542 4000);
PAINT MONO (-2542 4000);
FORCEPROP 2 LAST CDS_LIB mstr_standard
J 0
(-2200 4000);
PAINT ORANGE (-2200 4000);
DISPLAY INVISIBLE (-2200 4000);
FORCEPROP 1 LAST OFFPAGE TRUE
J 0
(-1875 3875);
DISPLAY 1.404255 (-1875 3875);
PAINT GREEN (-1875 3875);
DISPLAY INVISIBLE (-1875 3875);
FORCEPROP 1 LAST COMMENT_BODY TRUE
J 0
(-2075 3900);
DISPLAY 1.404255 (-2075 3900);
PAINT PEACH (-2075 3900);
DISPLAY INVISIBLE (-2075 3900);
FORCEPROP 2 LAST PATH I53
J 0
(-2450 4050);
DISPLAY 1.021277 (-2450 4050);
PAINT ORANGE (-2450 4050);
DISPLAY INVISIBLE (-2450 4050);
FORCEADD RES..2
(-2100 2350);
FORCEPROP 1 LAST LOCATION R4C8
J 0
(-2055 2475);
DISPLAY 0.617021 (-2055 2475);
PAINT AQUA (-2055 2475);
FORCEPROP 1 LAST PART_NUMBER G21796-026
J 0
(-2060 2225);
DISPLAY 0.617021 (-2060 2225);
PAINT BLUE (-2060 2225);
FORCEPROP 1 LAST VALUE 1.00K
J 0
(-2055 2425);
DISPLAY 0.617021 (-2055 2425);
PAINT SKYBLUE (-2055 2425);
FORCEPROP 1 LAST TOLERANCE 1%
J 0
(-2055 2375);
DISPLAY 0.617021 (-2055 2375);
PAINT SKYBLUE (-2055 2375);
FORCEPROP 1 LAST PACK_TYPE 0402
J 0
(-2060 2175);
DISPLAY 0.617021 (-2060 2175);
PAINT SKYBLUE (-2060 2175);
FORCEPROP 1 LAST MATERIAL CHIP
J 0
(-2060 2275);
DISPLAY 0.617021 (-2060 2275);
PAINT SKYBLUE (-2060 2275);
FORCEPROP 1 LAST WATTAGE 1/16W
J 0
(-2060 2325);
DISPLAY 0.617021 (-2060 2325);
PAINT SKYBLUE (-2060 2325);
FORCEPROP 1 LASTPIN (-2100 2250) $PN 2
J 0
(-2095 2260);
DISPLAY 0.617021 (-2095 2260);
PAINT WHITE (-2095 2260);
FORCEPROP 1 LASTPIN (-2100 2450) $PN 1
J 0
(-2095 2412);
DISPLAY 0.617021 (-2095 2412);
PAINT WHITE (-2095 2412);
FORCEPROP 2 LAST BOM_COST PROC_SIDEBAND
J 0
(-2100 2350);
DISPLAY 1.617021 (-2100 2350);
PAINT WHITE (-2100 2350);
DISPLAY INVISIBLE (-2100 2350);
FORCEPROP 2 LAST CDS_LIB mstr_discrete
J 0
(-2100 2350);
DISPLAY 1.617021 (-2100 2350);
PAINT ORANGE (-2100 2350);
DISPLAY INVISIBLE (-2100 2350);
FORCEPROP 2 LAST CDS_SEC 1
J 0
(-2050 2575);
DISPLAY 2.276596 (-2050 2575);
PAINT ORANGE (-2050 2575);
DISPLAY INVISIBLE (-2050 2575);
FORCEPROP 2 LAST $SEC 1
J 0
(-2050 2575);
DISPLAY 1.510638 (-2050 2575);
PAINT MONO (-2050 2575);
DISPLAY INVISIBLE (-2050 2575);
FORCEPROP 2 LAST CDS_LOCATION R4C8
J 0
(-2055 2475);
DISPLAY 0.617021 (-2055 2475);
PAINT AQUA (-2055 2475);
DISPLAY INVISIBLE (-2055 2475);
FORCEPROP 1 LAST PATH I55
J 0
(-2050 2525);
DISPLAY 0.978723 (-2050 2525);
PAINT WHITE (-2050 2525);
DISPLAY INVISIBLE (-2050 2525);
FORCEPROP 2 LAST ROOM PROC_RSTS_PGOODS
J 0
(-2075 2125);
DISPLAY 1.617021 (-2075 2125);
PAINT WHITE (-2075 2125);
DISPLAY INVISIBLE (-2075 2125);
FORCEADD OFFPAGE..1
(-2200 1800);
FORCEPROP 2 LAST $XR0 190 
J 0
(-2452 1800);
DISPLAY 0.638298 (-2452 1800);
PAINT MONO (-2452 1800);
FORCEPROP 2 LAST CDS_LIB mstr_standard
J 0
(-2200 1800);
PAINT ORANGE (-2200 1800);
DISPLAY INVISIBLE (-2200 1800);
FORCEPROP 1 LAST OFFPAGE TRUE
J 0
(-1875 1675);
DISPLAY 1.404255 (-1875 1675);
PAINT GREEN (-1875 1675);
DISPLAY INVISIBLE (-1875 1675);
FORCEPROP 1 LAST COMMENT_BODY TRUE
J 0
(-2075 1700);
DISPLAY 1.404255 (-2075 1700);
PAINT PEACH (-2075 1700);
DISPLAY INVISIBLE (-2075 1700);
FORCEPROP 2 LAST PATH I59
J 0
(-2450 1850);
DISPLAY 1.021277 (-2450 1850);
PAINT ORANGE (-2450 1850);
DISPLAY INVISIBLE (-2450 1850);
FORCEADD PVDDQ_ABC..1
(575 4700);
FORCEPROP 3 LASTPIN (575 4650) SIG_NAME PVDDQ_ABC\g
J 0
(585 4660);
DISPLAY 0.659574 (585 4660);
PAINT MONO (585 4660);
DISPLAY INVISIBLE (585 4660);
FORCEPROP 1 LAST VOLTAGE 1.2V
J 0
(530 4657);
DISPLAY 0.340426 (530 4657);
PAINT SKYBLUE (530 4657);
DISPLAY INVISIBLE (530 4657);
FORCEPROP 2 LAST CDS_LIB mstr_symbols
J 0
(575 4700);
PAINT ORANGE (575 4700);
DISPLAY INVISIBLE (575 4700);
FORCEPROP 1 LAST BODY_TYPE PLUMBING
J 0
(530 4657);
DISPLAY 0.340426 (530 4657);
PAINT GREEN (530 4657);
DISPLAY INVISIBLE (530 4657);
FORCEPROP 1 LAST PATH I6
J 0
(625 4725);
DISPLAY 0.872340 (625 4725);
PAINT AQUA (625 4725);
DISPLAY INVISIBLE (625 4725);
FORCEPROP 1 LAST HDL_POWER PVDDQ_ABC
J 1
(575 4750);
DISPLAY 0.872340 (575 4750);
PAINT GREEN (575 4750);
DISPLAY INVISIBLE (575 4750);
FORCEADD OFFPAGE..1
(-2200 1700);
FORCEPROP 2 LAST $XR0 190 
J 0
(-2452 1700);
DISPLAY 0.638298 (-2452 1700);
PAINT MONO (-2452 1700);
FORCEPROP 2 LAST $XR1 96 
J 0
(-2542 1700);
DISPLAY 0.638298 (-2542 1700);
PAINT MONO (-2542 1700);
FORCEPROP 2 LAST CDS_LIB mstr_standard
J 0
(-2200 1700);
PAINT ORANGE (-2200 1700);
DISPLAY INVISIBLE (-2200 1700);
FORCEPROP 1 LAST OFFPAGE TRUE
J 0
(-1875 1575);
DISPLAY 1.404255 (-1875 1575);
PAINT GREEN (-1875 1575);
DISPLAY INVISIBLE (-1875 1575);
FORCEPROP 1 LAST COMMENT_BODY TRUE
J 0
(-2075 1600);
DISPLAY 1.404255 (-2075 1600);
PAINT PEACH (-2075 1600);
DISPLAY INVISIBLE (-2075 1600);
FORCEPROP 2 LAST PATH I60
J 0
(-2450 1750);
DISPLAY 1.021277 (-2450 1750);
PAINT ORANGE (-2450 1750);
DISPLAY INVISIBLE (-2450 1750);
FORCEADD OFFPAGE..1
(-2200 1750);
FORCEPROP 2 LAST $XR0 190 
J 0
(-2452 1750);
DISPLAY 0.638298 (-2452 1750);
PAINT MONO (-2452 1750);
FORCEPROP 2 LAST CDS_LIB mstr_standard
J 0
(-2200 1750);
PAINT ORANGE (-2200 1750);
DISPLAY INVISIBLE (-2200 1750);
FORCEPROP 1 LAST OFFPAGE TRUE
J 0
(-1875 1625);
DISPLAY 1.404255 (-1875 1625);
PAINT GREEN (-1875 1625);
DISPLAY INVISIBLE (-1875 1625);
FORCEPROP 1 LAST COMMENT_BODY TRUE
J 0
(-2075 1650);
DISPLAY 1.404255 (-2075 1650);
PAINT PEACH (-2075 1650);
DISPLAY INVISIBLE (-2075 1650);
FORCEPROP 2 LAST PATH I61
J 0
(-2450 1800);
DISPLAY 1.021277 (-2450 1800);
PAINT ORANGE (-2450 1800);
DISPLAY INVISIBLE (-2450 1800);
FORCEADD P3V3_STBY..1
(-2100 2725);
FORCEPROP 3 LASTPIN (-2100 2675) SIG_NAME P3V3_STBY\g
J 0
(-2090 2685);
DISPLAY 0.659574 (-2090 2685);
PAINT MONO (-2090 2685);
DISPLAY INVISIBLE (-2090 2685);
FORCEPROP 1 LAST VOLTAGE 3.3V
J 0
(-2145 2682);
DISPLAY 0.340426 (-2145 2682);
PAINT SKYBLUE (-2145 2682);
DISPLAY INVISIBLE (-2145 2682);
FORCEPROP 2 LAST CDS_LIB mstr_symbols
J 0
(-2100 2725);
PAINT ORANGE (-2100 2725);
DISPLAY INVISIBLE (-2100 2725);
FORCEPROP 1 LAST SIZE 1B
J 0
(-2055 2747);
DISPLAY 0.340426 (-2055 2747);
PAINT GREEN (-2055 2747);
DISPLAY INVISIBLE (-2055 2747);
FORCEPROP 1 LAST BODY_TYPE PLUMBING
J 0
(-2145 2682);
DISPLAY 0.340426 (-2145 2682);
PAINT GREEN (-2145 2682);
DISPLAY INVISIBLE (-2145 2682);
FORCEPROP 1 LAST PATH I65
J 0
(-2055 2727);
DISPLAY 0.340426 (-2055 2727);
PAINT GREEN (-2055 2727);
DISPLAY INVISIBLE (-2055 2727);
FORCEPROP 1 LAST HDL_POWER P3V3_STBY
J 0
(-2400 2600);
DISPLAY 0.872340 (-2400 2600);
PAINT ORANGE (-2400 2600);
DISPLAY INVISIBLE (-2400 2600);
FORCEADD P3V3_STBY..1
(-2100 5050);
FORCEPROP 3 LASTPIN (-2100 5000) SIG_NAME P3V3_STBY\g
J 0
(-2090 5010);
DISPLAY 0.659574 (-2090 5010);
PAINT MONO (-2090 5010);
DISPLAY INVISIBLE (-2090 5010);
FORCEPROP 1 LAST VOLTAGE 3.3V
J 0
(-2145 5007);
DISPLAY 0.340426 (-2145 5007);
PAINT SKYBLUE (-2145 5007);
DISPLAY INVISIBLE (-2145 5007);
FORCEPROP 1 LAST SIZE 1B
J 0
(-2055 5072);
DISPLAY 0.340426 (-2055 5072);
PAINT GREEN (-2055 5072);
DISPLAY INVISIBLE (-2055 5072);
FORCEPROP 2 LAST CDS_LIB mstr_symbols
J 0
(-2100 5050);
PAINT ORANGE (-2100 5050);
DISPLAY INVISIBLE (-2100 5050);
FORCEPROP 1 LAST BODY_TYPE PLUMBING
J 0
(-2145 5007);
DISPLAY 0.340426 (-2145 5007);
PAINT GREEN (-2145 5007);
DISPLAY INVISIBLE (-2145 5007);
FORCEPROP 1 LAST PATH I68
J 0
(-2055 5052);
DISPLAY 0.340426 (-2055 5052);
PAINT GREEN (-2055 5052);
DISPLAY INVISIBLE (-2055 5052);
FORCEPROP 1 LAST HDL_POWER P3V3_STBY
J 0
(-2400 4925);
DISPLAY 0.872340 (-2400 4925);
PAINT ORANGE (-2400 4925);
DISPLAY INVISIBLE (-2400 4925);
FORCEADD RES..1
(-2400 2050);
FORCEPROP 1 LAST LOCATION R4C9
J 0
(-2450 2100);
DISPLAY 0.617021 (-2450 2100);
PAINT AQUA (-2450 2100);
FORCEPROP 1 LAST PART_NUMBER G21796-026
J 0
(-2450 2150);
DISPLAY 0.617021 (-2450 2150);
PAINT BLUE (-2450 2150);
FORCEPROP 1 LAST VALUE 1.00K
J 2
(-2425 1950);
DISPLAY 0.617021 (-2425 1950);
PAINT SKYBLUE (-2425 1950);
FORCEPROP 1 LAST TOLERANCE 1%
J 0
(-2400 1950);
DISPLAY 0.617021 (-2400 1950);
PAINT SKYBLUE (-2400 1950);
FORCEPROP 1 LAST PACK_TYPE 0402
J 0
(-2150 1900);
DISPLAY 0.617021 (-2150 1900);
PAINT SKYBLUE (-2150 1900);
FORCEPROP 1 LAST MATERIAL CHIP
J 0
(-2400 1900);
DISPLAY 0.617021 (-2400 1900);
PAINT SKYBLUE (-2400 1900);
FORCEPROP 1 LAST WATTAGE 1/16W
J 2
(-2425 1900);
DISPLAY 0.617021 (-2425 1900);
PAINT SKYBLUE (-2425 1900);
FORCEPROP 1 LASTPIN (-2300 2050) $PN 2
J 0
(-2338 2062);
DISPLAY 0.617021 (-2338 2062);
PAINT ORANGE (-2338 2062);
FORCEPROP 1 LASTPIN (-2500 2050) $PN 1
J 0
(-2488 2062);
DISPLAY 0.617021 (-2488 2062);
PAINT ORANGE (-2488 2062);
FORCEPROP 0 LAST BOM_COST PROC_SIDEBAND
J 0
(-2450 2350);
DISPLAY 1.021277 (-2450 2350);
PAINT ORANGE (-2450 2350);
DISPLAY INVISIBLE (-2450 2350);
FORCEPROP 2 LAST SEC_TYPE 0402
J 0
(-2450 2250);
DISPLAY 1.021277 (-2450 2250);
PAINT ORANGE (-2450 2250);
DISPLAY INVISIBLE (-2450 2250);
FORCEPROP 2 LAST CDS_LIB mstr_discrete
J 0
(-2400 2050);
PAINT ORANGE (-2400 2050);
DISPLAY INVISIBLE (-2400 2050);
FORCEPROP 2 LAST SEC 1
J 0
(-2450 2250);
DISPLAY 0.680851 (-2450 2250);
PAINT MONO (-2450 2250);
DISPLAY INVISIBLE (-2450 2250);
FORCEPROP 2 LAST CDS_LOCATION R4C9
J 0
(-2450 2100);
DISPLAY 0.617021 (-2450 2100);
PAINT AQUA (-2450 2100);
DISPLAY INVISIBLE (-2450 2100);
FORCEPROP 1 LAST PATH I69
J 0
(-2450 2200);
DISPLAY 0.978723 (-2450 2200);
PAINT WHITE (-2450 2200);
DISPLAY INVISIBLE (-2450 2200);
FORCEPROP 2 LAST ROOM PROC_RSTS_PGOODS
J 0
(-2450 2250);
DISPLAY 1.021277 (-2450 2250);
PAINT ORANGE (-2450 2250);
DISPLAY INVISIBLE (-2450 2250);
FORCEADD RES..2
(575 4450);
FORCEPROP 1 LAST LOCATION R3P38
J 0
(620 4575);
DISPLAY 0.617021 (620 4575);
PAINT AQUA (620 4575);
FORCEPROP 1 LAST PART_NUMBER G21796-298
J 0
(615 4325);
DISPLAY 0.617021 (615 4325);
PAINT BLUE (615 4325);
FORCEPROP 1 LAST VALUE 64.9
J 0
(620 4525);
DISPLAY 0.617021 (620 4525);
PAINT SKYBLUE (620 4525);
FORCEPROP 1 LAST TOLERANCE 1.0%
J 0
(620 4475);
DISPLAY 0.617021 (620 4475);
PAINT SKYBLUE (620 4475);
FORCEPROP 1 LAST PACK_TYPE 0402
J 0
(615 4275);
DISPLAY 0.617021 (615 4275);
PAINT SKYBLUE (615 4275);
FORCEPROP 1 LAST MATERIAL CHIP
J 0
(615 4375);
DISPLAY 0.617021 (615 4375);
PAINT SKYBLUE (615 4375);
FORCEPROP 1 LAST WATTAGE 1/16W
J 0
(615 4425);
DISPLAY 0.617021 (615 4425);
PAINT SKYBLUE (615 4425);
FORCEPROP 1 LASTPIN (575 4350) $PN 2
J 0
(580 4360);
DISPLAY 0.617021 (580 4360);
PAINT WHITE (580 4360);
FORCEPROP 1 LASTPIN (575 4550) $PN 1
J 0
(580 4512);
DISPLAY 0.617021 (580 4512);
PAINT WHITE (580 4512);
FORCEPROP 2 LAST BOM_COST PROC_SIDEBAND
J 0
(625 4625);
DISPLAY 1.659574 (625 4625);
PAINT WHITE (625 4625);
DISPLAY INVISIBLE (625 4625);
FORCEPROP 2 LAST CDS_LIB mstr_discrete
J 0
(575 4450);
DISPLAY 1.617021 (575 4450);
PAINT ORANGE (575 4450);
DISPLAY INVISIBLE (575 4450);
FORCEPROP 2 LAST CDS_SEC 1
J 0
(625 4675);
DISPLAY 2.276596 (625 4675);
PAINT ORANGE (625 4675);
DISPLAY INVISIBLE (625 4675);
FORCEPROP 2 LAST $SEC 1
J 0
(625 4675);
DISPLAY 1.510638 (625 4675);
PAINT MONO (625 4675);
DISPLAY INVISIBLE (625 4675);
FORCEPROP 2 LAST CDS_LOCATION R3P38
J 0
(620 4575);
DISPLAY 0.617021 (620 4575);
PAINT AQUA (620 4575);
DISPLAY INVISIBLE (620 4575);
FORCEPROP 1 LAST PATH I7
J 0
(625 4625);
DISPLAY 0.978723 (625 4625);
PAINT WHITE (625 4625);
DISPLAY INVISIBLE (625 4625);
FORCEPROP 2 LAST ROOM PROC_RSTS_PGOODS
J 0
(625 4625);
DISPLAY 2.276596 (625 4625);
PAINT WHITE (625 4625);
DISPLAY INVISIBLE (625 4625);
FORCEADD GND..1
(-2875 1950);
FORCEPROP 3 LASTPIN (-2875 2000) SIG_NAME GND\g
J 0
(-2865 2010);
DISPLAY 0.659574 (-2865 2010);
PAINT MONO (-2865 2010);
DISPLAY INVISIBLE (-2865 2010);
FORCEPROP 1 LAST VOLTAGE 0.0V
J 0
(-2920 1907);
DISPLAY 0.340426 (-2920 1907);
PAINT SKYBLUE (-2920 1907);
DISPLAY INVISIBLE (-2920 1907);
FORCEPROP 2 LAST CDS_LIB mstr_symbols
J 0
(-2875 1950);
PAINT ORANGE (-2875 1950);
DISPLAY INVISIBLE (-2875 1950);
FORCEPROP 1 LAST SIZE 1B
J 0
(-2800 1900);
DISPLAY 1.893617 (-2800 1900);
PAINT GREEN (-2800 1900);
DISPLAY INVISIBLE (-2800 1900);
FORCEPROP 1 LAST BODY_TYPE PLUMBING
J 0
(-2920 1907);
DISPLAY 0.340426 (-2920 1907);
PAINT GREEN (-2920 1907);
DISPLAY INVISIBLE (-2920 1907);
FORCEPROP 1 LAST PATH I70
J 0
(-2800 1950);
DISPLAY 0.872340 (-2800 1950);
PAINT AQUA (-2800 1950);
DISPLAY INVISIBLE (-2800 1950);
FORCEPROP 1 LAST HDL_POWER GND
J 0
(-2875 2100);
DISPLAY 1.595745 (-2875 2100);
PAINT GREEN (-2875 2100);
DISPLAY INVISIBLE (-2875 2100);
FORCEADD RES..1
(-2400 4350);
FORCEPROP 1 LAST LOCATION R3P32
J 0
(-2450 4400);
DISPLAY 0.617021 (-2450 4400);
PAINT AQUA (-2450 4400);
FORCEPROP 1 LAST PART_NUMBER G21796-026
J 0
(-2450 4450);
DISPLAY 0.617021 (-2450 4450);
PAINT BLUE (-2450 4450);
FORCEPROP 1 LAST VALUE 1.00K
J 2
(-2425 4250);
DISPLAY 0.617021 (-2425 4250);
PAINT SKYBLUE (-2425 4250);
FORCEPROP 1 LAST TOLERANCE 1%
J 0
(-2400 4250);
DISPLAY 0.617021 (-2400 4250);
PAINT SKYBLUE (-2400 4250);
FORCEPROP 1 LAST PACK_TYPE 0402
J 0
(-2650 4225);
DISPLAY 0.617021 (-2650 4225);
PAINT SKYBLUE (-2650 4225);
FORCEPROP 1 LAST MATERIAL CHIP
J 0
(-2400 4200);
DISPLAY 0.617021 (-2400 4200);
PAINT SKYBLUE (-2400 4200);
FORCEPROP 1 LAST WATTAGE 1/16W
J 2
(-2425 4200);
DISPLAY 0.617021 (-2425 4200);
PAINT SKYBLUE (-2425 4200);
FORCEPROP 1 LASTPIN (-2300 4350) $PN 2
J 0
(-2338 4362);
DISPLAY 0.617021 (-2338 4362);
PAINT ORANGE (-2338 4362);
FORCEPROP 1 LASTPIN (-2500 4350) $PN 1
J 0
(-2488 4362);
DISPLAY 0.617021 (-2488 4362);
PAINT ORANGE (-2488 4362);
FORCEPROP 0 LAST BOM_COST PROC_SIDEBAND
J 0
(-2450 4650);
DISPLAY 1.021277 (-2450 4650);
PAINT ORANGE (-2450 4650);
DISPLAY INVISIBLE (-2450 4650);
FORCEPROP 2 LAST SEC_TYPE 0402
J 0
(-2450 4550);
DISPLAY 1.021277 (-2450 4550);
PAINT ORANGE (-2450 4550);
DISPLAY INVISIBLE (-2450 4550);
FORCEPROP 2 LAST CDS_LIB mstr_discrete
J 0
(-2400 4350);
PAINT ORANGE (-2400 4350);
DISPLAY INVISIBLE (-2400 4350);
FORCEPROP 2 LAST SEC 1
J 0
(-2450 4550);
DISPLAY 0.680851 (-2450 4550);
PAINT MONO (-2450 4550);
DISPLAY INVISIBLE (-2450 4550);
FORCEPROP 2 LAST CDS_LOCATION R3P32
J 0
(-2450 4400);
DISPLAY 0.617021 (-2450 4400);
PAINT AQUA (-2450 4400);
DISPLAY INVISIBLE (-2450 4400);
FORCEPROP 1 LAST PATH I71
J 0
(-2450 4500);
DISPLAY 0.978723 (-2450 4500);
PAINT WHITE (-2450 4500);
DISPLAY INVISIBLE (-2450 4500);
FORCEPROP 2 LAST ROOM PROC_RSTS_PGOODS
J 0
(-2450 4550);
DISPLAY 1.021277 (-2450 4550);
PAINT ORANGE (-2450 4550);
DISPLAY INVISIBLE (-2450 4550);
FORCEADD GND..1
(-2775 4225);
FORCEPROP 3 LASTPIN (-2775 4275) SIG_NAME GND\g
J 0
(-2765 4285);
DISPLAY 0.659574 (-2765 4285);
PAINT MONO (-2765 4285);
DISPLAY INVISIBLE (-2765 4285);
FORCEPROP 1 LAST VOLTAGE 0.0V
J 0
(-2820 4182);
DISPLAY 0.340426 (-2820 4182);
PAINT SKYBLUE (-2820 4182);
DISPLAY INVISIBLE (-2820 4182);
FORCEPROP 1 LAST SIZE 1B
J 0
(-2700 4175);
DISPLAY 1.893617 (-2700 4175);
PAINT GREEN (-2700 4175);
DISPLAY INVISIBLE (-2700 4175);
FORCEPROP 2 LAST CDS_LIB mstr_symbols
J 0
(-2775 4225);
PAINT ORANGE (-2775 4225);
DISPLAY INVISIBLE (-2775 4225);
FORCEPROP 1 LAST BODY_TYPE PLUMBING
J 0
(-2820 4182);
DISPLAY 0.340426 (-2820 4182);
PAINT GREEN (-2820 4182);
DISPLAY INVISIBLE (-2820 4182);
FORCEPROP 1 LAST PATH I72
J 0
(-2700 4225);
DISPLAY 0.872340 (-2700 4225);
PAINT AQUA (-2700 4225);
DISPLAY INVISIBLE (-2700 4225);
FORCEPROP 1 LAST HDL_POWER GND
J 0
(-2775 4375);
DISPLAY 1.595745 (-2775 4375);
PAINT GREEN (-2775 4375);
DISPLAY INVISIBLE (-2775 4375);
FORCEADD CAP_A..1
(-1650 4650);
FORCEPROP 1 LAST LOCATION C3P42
J 0
(-1600 4750);
DISPLAY 0.617021 (-1600 4750);
PAINT AQUA (-1600 4750);
FORCEPROP 1 LAST PART_NUMBER D97712-004
J 0
(-1600 4500);
DISPLAY 0.617021 (-1600 4500);
PAINT BLUE (-1600 4500);
FORCEPROP 1 LAST VALUE 1.0UF
J 0
(-1600 4700);
DISPLAY 0.617021 (-1600 4700);
PAINT SKYBLUE (-1600 4700);
FORCEPROP 1 LAST TOLERANCE 10%
J 0
(-1600 4600);
DISPLAY 0.617021 (-1600 4600);
PAINT SKYBLUE (-1600 4600);
FORCEPROP 1 LAST PACK_TYPE 0402V
J 0
(-1600 4450);
DISPLAY 0.617021 (-1600 4450);
PAINT SKYBLUE (-1600 4450);
FORCEPROP 1 LAST VOLTAGE 6.3V
J 0
(-1600 4650);
DISPLAY 0.617021 (-1600 4650);
PAINT SKYBLUE (-1600 4650);
FORCEPROP 1 LAST MATERIAL X6S
J 0
(-1600 4550);
DISPLAY 0.617021 (-1600 4550);
PAINT SKYBLUE (-1600 4550);
FORCEPROP 1 LASTPIN (-1650 4750) $PN 1
J 0
(-1640 4730);
DISPLAY 0.617021 (-1640 4730);
PAINT WHITE (-1640 4730);
FORCEPROP 1 LASTPIN (-1650 4550) $PN 2
J 0
(-1640 4530);
DISPLAY 0.617021 (-1640 4530);
PAINT WHITE (-1640 4530);
FORCEPROP 2 LAST CDS_LOCATION C3P42
J 0
(-1600 4750);
DISPLAY 0.617021 (-1600 4750);
PAINT AQUA (-1600 4750);
DISPLAY INVISIBLE (-1600 4750);
FORCEPROP 2 LAST BOM_COST PROC_SIDEBAND
J 0
(-1650 4650);
DISPLAY 1.617021 (-1650 4650);
PAINT WHITE (-1650 4650);
DISPLAY INVISIBLE (-1650 4650);
FORCEPROP 2 LAST CDS_LIB dev_discrete
J 0
(-1650 4650);
PAINT ORANGE (-1650 4650);
DISPLAY INVISIBLE (-1650 4650);
FORCEPROP 2 LAST CDS_SEC 1
J 0
(-1600 4800);
PAINT ORANGE (-1600 4800);
DISPLAY INVISIBLE (-1600 4800);
FORCEPROP 2 LAST SEC_TYPE 0402V
J 0
(-1600 4850);
DISPLAY 1.617021 (-1600 4850);
PAINT MONO (-1600 4850);
DISPLAY INVISIBLE (-1600 4850);
FORCEPROP 2 LAST SEC 1
J 0
(-1600 4850);
DISPLAY 1.510638 (-1600 4850);
PAINT MONO (-1600 4850);
DISPLAY INVISIBLE (-1600 4850);
FORCEPROP 1 LAST PATH I73
J 0
(-1600 4800);
DISPLAY 0.978723 (-1600 4800);
PAINT WHITE (-1600 4800);
DISPLAY INVISIBLE (-1600 4800);
FORCEPROP 2 LAST ROOM PROC_RSTS_PGOODS
J 0
(-1600 4400);
DISPLAY 1.617021 (-1600 4400);
PAINT WHITE (-1600 4400);
DISPLAY INVISIBLE (-1600 4400);
FORCEADD GND..1
(-1650 4450);
FORCEPROP 3 LASTPIN (-1650 4500) SIG_NAME GND\g
J 0
(-1640 4510);
DISPLAY 0.659574 (-1640 4510);
PAINT MONO (-1640 4510);
DISPLAY INVISIBLE (-1640 4510);
FORCEPROP 1 LAST VOLTAGE 0.0V
J 0
(-1695 4407);
DISPLAY 0.340426 (-1695 4407);
PAINT SKYBLUE (-1695 4407);
DISPLAY INVISIBLE (-1695 4407);
FORCEPROP 2 LAST CDS_LIB mstr_symbols
J 0
(-1650 4450);
DISPLAY 2.212766 (-1650 4450);
PAINT ORANGE (-1650 4450);
DISPLAY INVISIBLE (-1650 4450);
FORCEPROP 1 LAST SIZE 1B
J 0
(-1575 4400);
DISPLAY 1.893617 (-1575 4400);
PAINT GREEN (-1575 4400);
DISPLAY INVISIBLE (-1575 4400);
FORCEPROP 1 LAST BODY_TYPE PLUMBING
J 0
(-1695 4407);
DISPLAY 0.340426 (-1695 4407);
PAINT GREEN (-1695 4407);
DISPLAY INVISIBLE (-1695 4407);
FORCEPROP 1 LAST PATH I74
J 0
(-1575 4450);
DISPLAY 0.872340 (-1575 4450);
PAINT AQUA (-1575 4450);
DISPLAY INVISIBLE (-1575 4450);
FORCEPROP 1 LAST HDL_POWER GND
J 0
(-1650 4600);
DISPLAY 1.595745 (-1650 4600);
PAINT GREEN (-1650 4600);
DISPLAY INVISIBLE (-1650 4600);
FORCEADD CAP_A..1
(-1725 2325);
FORCEPROP 1 LAST LOCATION C4C3
J 0
(-1675 2425);
DISPLAY 0.617021 (-1675 2425);
PAINT AQUA (-1675 2425);
FORCEPROP 1 LAST PART_NUMBER D97712-004
J 0
(-1675 2175);
DISPLAY 0.617021 (-1675 2175);
PAINT BLUE (-1675 2175);
FORCEPROP 1 LAST VALUE 1.0UF
J 0
(-1675 2375);
DISPLAY 0.617021 (-1675 2375);
PAINT SKYBLUE (-1675 2375);
FORCEPROP 1 LAST TOLERANCE 10%
J 0
(-1675 2275);
DISPLAY 0.617021 (-1675 2275);
PAINT SKYBLUE (-1675 2275);
FORCEPROP 1 LAST PACK_TYPE 0402V
J 0
(-1675 2125);
DISPLAY 0.617021 (-1675 2125);
PAINT SKYBLUE (-1675 2125);
FORCEPROP 1 LAST VOLTAGE 6.3V
J 0
(-1675 2325);
DISPLAY 0.617021 (-1675 2325);
PAINT SKYBLUE (-1675 2325);
FORCEPROP 1 LAST MATERIAL X6S
J 0
(-1675 2225);
DISPLAY 0.617021 (-1675 2225);
PAINT SKYBLUE (-1675 2225);
FORCEPROP 1 LASTPIN (-1725 2425) $PN 1
J 0
(-1715 2405);
DISPLAY 0.617021 (-1715 2405);
PAINT WHITE (-1715 2405);
FORCEPROP 1 LASTPIN (-1725 2225) $PN 2
J 0
(-1715 2205);
DISPLAY 0.617021 (-1715 2205);
PAINT WHITE (-1715 2205);
FORCEPROP 2 LAST CDS_LOCATION C4C3
J 0
(-1675 2425);
DISPLAY 0.617021 (-1675 2425);
PAINT AQUA (-1675 2425);
DISPLAY INVISIBLE (-1675 2425);
FORCEPROP 2 LAST BOM_COST PROC_SIDEBAND
J 0
(-1725 2325);
DISPLAY 1.617021 (-1725 2325);
PAINT WHITE (-1725 2325);
DISPLAY INVISIBLE (-1725 2325);
FORCEPROP 2 LAST CDS_LIB dev_discrete
J 0
(-1725 2325);
PAINT ORANGE (-1725 2325);
DISPLAY INVISIBLE (-1725 2325);
FORCEPROP 2 LAST CDS_SEC 1
J 0
(-1675 2475);
PAINT ORANGE (-1675 2475);
DISPLAY INVISIBLE (-1675 2475);
FORCEPROP 2 LAST SEC_TYPE 0402V
J 0
(-1675 2525);
DISPLAY 1.617021 (-1675 2525);
PAINT MONO (-1675 2525);
DISPLAY INVISIBLE (-1675 2525);
FORCEPROP 2 LAST SEC 1
J 0
(-1675 2525);
DISPLAY 1.510638 (-1675 2525);
PAINT MONO (-1675 2525);
DISPLAY INVISIBLE (-1675 2525);
FORCEPROP 1 LAST PATH I75
J 0
(-1675 2475);
DISPLAY 0.978723 (-1675 2475);
PAINT WHITE (-1675 2475);
DISPLAY INVISIBLE (-1675 2475);
FORCEPROP 2 LAST ROOM PROC_RSTS_PGOODS
J 0
(-1675 2075);
DISPLAY 1.617021 (-1675 2075);
PAINT WHITE (-1675 2075);
DISPLAY INVISIBLE (-1675 2075);
FORCEADD GND..1
(-1725 2125);
FORCEPROP 3 LASTPIN (-1725 2175) SIG_NAME GND\g
J 0
(-1715 2185);
DISPLAY 0.659574 (-1715 2185);
PAINT MONO (-1715 2185);
DISPLAY INVISIBLE (-1715 2185);
FORCEPROP 1 LAST VOLTAGE 0.0V
J 0
(-1770 2082);
DISPLAY 0.340426 (-1770 2082);
PAINT SKYBLUE (-1770 2082);
DISPLAY INVISIBLE (-1770 2082);
FORCEPROP 2 LAST CDS_LIB mstr_symbols
J 0
(-1725 2125);
DISPLAY 2.212766 (-1725 2125);
PAINT ORANGE (-1725 2125);
DISPLAY INVISIBLE (-1725 2125);
FORCEPROP 1 LAST SIZE 1B
J 0
(-1650 2075);
DISPLAY 1.893617 (-1650 2075);
PAINT GREEN (-1650 2075);
DISPLAY INVISIBLE (-1650 2075);
FORCEPROP 1 LAST BODY_TYPE PLUMBING
J 0
(-1770 2082);
DISPLAY 0.340426 (-1770 2082);
PAINT GREEN (-1770 2082);
DISPLAY INVISIBLE (-1770 2082);
FORCEPROP 1 LAST PATH I76
J 0
(-1650 2125);
DISPLAY 0.872340 (-1650 2125);
PAINT AQUA (-1650 2125);
DISPLAY INVISIBLE (-1650 2125);
FORCEPROP 1 LAST HDL_POWER GND
J 0
(-1725 2275);
DISPLAY 1.595745 (-1725 2275);
PAINT GREEN (-1725 2275);
DISPLAY INVISIBLE (-1725 2275);
FORCEADD OFFPAGE..2
(3375 4100);
FORCEPROP 2 LAST $XR0 21 
J 0
(3564 4100);
DISPLAY 0.638298 (3564 4100);
PAINT MONO (3564 4100);
FORCEPROP 2 LAST $XR1 113 
J 0
(3654 4100);
DISPLAY 0.638298 (3654 4100);
PAINT MONO (3654 4100);
FORCEPROP 2 LAST CDS_LIB mstr_standard
J 0
(3375 4100);
PAINT ORANGE (3375 4100);
DISPLAY INVISIBLE (3375 4100);
FORCEPROP 1 LAST OFFPAGE TRUE
J 0
(3700 3975);
DISPLAY 1.404255 (3700 3975);
PAINT GREEN (3700 3975);
DISPLAY INVISIBLE (3700 3975);
FORCEPROP 1 LAST COMMENT_BODY TRUE
J 0
(3330 4005);
DISPLAY 1.404255 (3330 4005);
PAINT PEACH (3330 4005);
DISPLAY INVISIBLE (3330 4005);
FORCEPROP 2 LAST PATH I8
J 0
(3625 4150);
DISPLAY 1.021277 (3625 4150);
PAINT ORANGE (3625 4150);
DISPLAY INVISIBLE (3625 4150);
FORCEADD OFFPAGE..2
(3375 3875);
FORCEPROP 2 LAST $XR0 21 
J 0
(3564 3875);
DISPLAY 0.638298 (3564 3875);
PAINT MONO (3564 3875);
FORCEPROP 2 LAST CDS_LIB mstr_standard
J 0
(3375 3875);
PAINT ORANGE (3375 3875);
DISPLAY INVISIBLE (3375 3875);
FORCEPROP 1 LAST OFFPAGE TRUE
J 0
(3700 3750);
DISPLAY 1.404255 (3700 3750);
PAINT GREEN (3700 3750);
DISPLAY INVISIBLE (3700 3750);
FORCEPROP 1 LAST COMMENT_BODY TRUE
J 0
(3330 3780);
DISPLAY 1.404255 (3330 3780);
PAINT PEACH (3330 3780);
DISPLAY INVISIBLE (3330 3780);
FORCEPROP 2 LAST PATH I9
J 0
(3575 3925);
DISPLAY 1.021277 (3575 3925);
PAINT ORANGE (3575 3925);
DISPLAY INVISIBLE (3575 3925);
FORCEADD DESIGN_NOTE..1
(-1050 3375);
PAINT PURPLE (-1050 3375);
FORCEPROP 0 LAST L3 AND VREF PIN IS NOT USED
J 0
(-1250 3150);
DISPLAY 0.808511 (-1250 3150);
PAINT VIOLET (-1250 3150);
FORCEPROP 0 LAST L2 THE PINS 'AX' ARE INPUTS & 'BX' OUTPUTS ARE OPEN-DRAIN
J 0
(-1250 3200);
DISPLAY 0.808511 (-1250 3200);
PAINT VIOLET (-1250 3200);
FORCEPROP 0 LAST L1 THE GTL2014 IS BEING USED AS LVTTL TO GTL CONVERTER, SO
J 0
(-1250 3250);
DISPLAY 0.808511 (-1250 3250);
PAINT VIOLET (-1250 3250);
FORCEPROP 2 LAST CDS_LIB mstr_symbols
J 0
(-1050 3375);
PAINT ORANGE (-1050 3375);
DISPLAY INVISIBLE (-1050 3375);
FORCEPROP 2 LAST BOM_COST SM_CONTROLLER
J 0
(-1250 3325);
PAINT MONO (-1250 3325);
DISPLAY INVISIBLE (-1250 3325);
FORCEPROP 1 LAST COMMENT_BODY TRUE
J 0
(-1025 3475);
DISPLAY 1.319149 (-1025 3475);
PAINT GREEN (-1025 3475);
DISPLAY INVISIBLE (-1025 3475);
FORCEPROP 2 LAST ROOM PROC_RSTS_PGOODS
J 0
(-1250 3325);
PAINT MONO (-1250 3325);
DISPLAY INVISIBLE (-1250 3325);
FORCEADD CAD_NOTE..1
(550 2700);
FORCEPROP 0 LAST TEXT1 PLACE PU RESISTORS NEAR CPU1
J 0
(425 2550);
DISPLAY 1.255319 (425 2550);
PAINT WHITE (425 2550);
FORCEPROP 2 LAST CDS_LIB mstr_symbols
J 0
(550 2700);
PAINT ORANGE (550 2700);
DISPLAY INVISIBLE (550 2700);
FORCEPROP 1 LAST COMMENT_BODY TRUE
J 0
(575 2800);
DISPLAY 1.595745 (575 2800);
PAINT PEACH (575 2800);
DISPLAY INVISIBLE (575 2800);
FORCEADD INTEL_CORP_BPAGE..1
(4400 350);
FORCEPROP 1 LAST CDS_CON_LAST_MODIFIED Tue Dec 01 11:51:49 2015
J 0
(2975 675);
PAINT ORANGE (2975 675);
DISPLAY INVISIBLE (2975 675);
FORCEPROP 1 LAST CUSTOM_TXT_CDS <CURRENT_DESIGN_SHEET> OF <TOTAL_DESIGN_SHEETS>
J 0
(3900 375);
PAINT GREEN (3900 375);
FORCEPROP 1 LAST CUSTOM_TXT_CDS <CON_LAST_MODIFIED>
J 0
(2475 700);
PAINT GREEN (2475 700);
FORCEPROP 2 LAST CUSTOM_TXT_CDS <XR_PAGE_TITLE>
J 0
(-3490 5600);
DISPLAY 0.638298 (-3490 5600);
PAINT PINK (-3490 5600);
DISPLAY INVISIBLE (-3490 5600);
FORCEPROP 1 LAST SCH_ADDRESS3 Santa Clara, CA 95052-8119
J 0
(425 375);
DISPLAY 0.617021 (425 375);
PAINT GREEN (425 375);
FORCEPROP 1 LAST SCH_ADDRESS2 P.O. BOX 58119
J 0
(425 425);
DISPLAY 0.617021 (425 425);
PAINT GREEN (425 425);
FORCEPROP 1 LAST SCH_ADDRESS1 2200 Mission College Blvd.
J 0
(425 475);
DISPLAY 0.617021 (425 475);
PAINT GREEN (425 475);
FORCEPROP 1 LAST SCH_TITLE CPU SIDE BAND:RESETS & POWER GOODS
J 0
(-3550 400);
DISPLAY 1.212766 (-3550 400);
PAINT ORANGE (-3550 400);
FORCEPROP 1 LAST SCH_NUMBER H4694802
J 0
(3100 500);
DISPLAY 1.212766 (3100 500);
PAINT YELLOW (3100 500);
FORCEPROP 1 LAST SCH_DEPT BESD
J 1
(-50 450);
DISPLAY 1.212766 (-50 450);
PAINT YELLOW (-50 450);
FORCEPROP 1 LAST SCH_REV 2.420
J 0
(4150 500);
DISPLAY 0.978723 (4150 500);
PAINT YELLOW (4150 500);
FORCEPROP 2 LAST PAGE_BORDER TRUE
J 0
(-3490 5600);
DISPLAY 0.638298 (-3490 5600);
PAINT PINK (-3490 5600);
DISPLAY INVISIBLE (-3490 5600);
FORCEPROP 2 LAST CDS_LIB mstr_symbols
J 0
(4400 350);
PAINT MONO (4400 350);
DISPLAY INVISIBLE (4400 350);
FORCEPROP 1 LAST COMMENT_BODY TRUE
J 0
(4412 362);
DISPLAY 0.468085 (4412 362);
PAINT GREEN (4412 362);
DISPLAY INVISIBLE (4412 362);
FORCEPROP 2 LAST CDS_XR_PAGE_TITLE CR-96 : @BASEBOARD_FAB2_LIB.BASEBOARD_FAB2(SCH_1):PAGE96
J 0
(-3490 5600);
DISPLAY 0.638298 (-3490 5600);
PAINT PINK (-3490 5600);
DISPLAY INVISIBLE (-3490 5600);
FORCEADD DESIGN_NOTE..1
(-1075 1125);
PAINT PURPLE (-1075 1125);
FORCEPROP 0 LAST L3 AND VREF PIN IS NOT USED
J 0
(-1275 900);
DISPLAY 0.808511 (-1275 900);
PAINT VIOLET (-1275 900);
FORCEPROP 0 LAST L1 THE GTL2014 IS BEING USED AS LVTTL TO GTL CONVERTER, SO
J 0
(-1275 1000);
DISPLAY 0.808511 (-1275 1000);
PAINT VIOLET (-1275 1000);
FORCEPROP 0 LAST L2 THE PINS 'AX' ARE INPUTS & 'BX' OUTPUTS ARE OPEN-DRAIN
J 0
(-1275 950);
DISPLAY 0.808511 (-1275 950);
PAINT VIOLET (-1275 950);
FORCEPROP 2 LAST CDS_LIB mstr_symbols
J 0
(-1075 1125);
PAINT ORANGE (-1075 1125);
DISPLAY INVISIBLE (-1075 1125);
FORCEPROP 2 LAST BOM_COST SM_CONTROLLER
J 0
(-1275 1075);
PAINT MONO (-1275 1075);
DISPLAY INVISIBLE (-1275 1075);
FORCEPROP 1 LAST COMMENT_BODY TRUE
J 0
(-1050 1225);
DISPLAY 1.319149 (-1050 1225);
PAINT GREEN (-1050 1225);
DISPLAY INVISIBLE (-1050 1225);
FORCEPROP 2 LAST ROOM PROC_RSTS_PGOODS
J 0
(-1275 1075);
PAINT MONO (-1275 1075);
DISPLAY INVISIBLE (-1275 1075);
FORCEADD CAD_NOTE..1
(650 5000);
FORCEPROP 0 LAST TEXT1 PLACE PU RESISTORS NEAR CPU0
J 0
(525 4850);
DISPLAY 1.255319 (525 4850);
PAINT WHITE (525 4850);
FORCEPROP 2 LAST CDS_LIB mstr_symbols
J 0
(650 5000);
PAINT ORANGE (650 5000);
DISPLAY INVISIBLE (650 5000);
FORCEPROP 1 LAST COMMENT_BODY TRUE
J 0
(675 5100);
DISPLAY 1.595745 (675 5100);
PAINT PEACH (675 5100);
DISPLAY INVISIBLE (675 5100);
WIRE 16 -1 (1900 4550)(1900 4600);
WIRE 16 -1 (1900 4600)(1800 4600);
WIRE 16 -1 (1800 4600)(1700 4600);
WIRE 16 -1 (1800 4600)(1800 4650);
WIRE 16 -1 (1700 4550)(1700 4600);
WIRE 16 -1 (1900 2250)(1900 2300);
WIRE 16 -1 (1900 2300)(1800 2300);
WIRE 16 -1 (1800 2300)(1700 2300);
WIRE 16 -1 (1800 2300)(1800 2375);
WIRE 16 -1 (1700 2250)(1700 2300);
WIRE 16 -1 (975 2250)(975 2350);
WIRE 16 -1 (575 2250)(575 2350);
WIRE 16 -1 (975 4550)(975 4650);
WIRE 16 -1 (-425 3800)(-325 3800);
WIRE 16 -1 (-325 3800)(-325 3750);
WIRE 16 -1 (-425 3750)(-325 3750);
WIRE 16 -1 (-325 3750)(-325 3700);
WIRE 16 -1 (-425 3700)(-325 3700);
WIRE 16 -1 (-325 3700)(-325 3600);
WIRE 16 -1 (-425 1500)(-325 1500);
WIRE 16 -1 (-325 1500)(-325 1450);
WIRE 16 -1 (-425 1450)(-325 1450);
WIRE 16 -1 (-325 1450)(-325 1400);
WIRE 16 -1 (-425 1400)(-325 1400);
WIRE 16 -1 (-325 1400)(-325 1300);
WIRE 16 -1 (575 4550)(575 4650);
WIRE 16 -1 (-1425 2100)(-1325 2100);
WIRE 16 -1 (-1425 2550)(-1425 2100);
WIRE 16 -1 (-1725 2550)(-1425 2550);
WIRE 16 -1 (-1725 2425)(-1725 2550);
WIRE 16 -1 (-2100 2550)(-1725 2550);
WIRE 16 -1 (-2100 2450)(-2100 2550);
WIRE 16 -1 (-2100 2675)(-2100 2550);
WIRE 16 -1 (-1400 4850)(-1400 4400);
WIRE 16 -1 (-1650 4850)(-1400 4850);
WIRE 16 -1 (-1400 4400)(-1325 4400);
WIRE 16 -1 (-1650 4750)(-1650 4850);
WIRE 16 -1 (-2100 4850)(-1650 4850);
WIRE 16 -1 (-2100 4750)(-2100 4850);
WIRE 16 -1 (-2100 4850)(-2100 5000);
WIRE 16 -1 (-2500 2050)(-2875 2050);
WIRE 16 -1 (-2875 2050)(-2875 2000);
WIRE 16 -1 (-2500 4350)(-2775 4350);
WIRE 16 -1 (-2775 4350)(-2775 4275);
WIRE 16 -1 (-1650 4500)(-1650 4550);
WIRE 16 -1 (-1725 2225)(-1725 2175);
WIRE 16 -1 (-2100 1575)(-2350 1575);
WIRE 16 -1 (-2100 1575)(-2100 1450);
WIRE 16 -1 (-2350 1575)(-2350 1450);
WIRE 16 -1 (-2350 1450)(-2100 1450);
WIRE 16 -1 (-2075 1600)(-2375 1600);
WIRE 16 -1 (-2075 1600)(-2075 1425);
WIRE 16 -1 (-2375 1600)(-2375 1425);
WIRE 16 -1 (-2075 1425)(-2375 1425);
WIRE 16 -1 (-2075 3900)(-2075 3725);
WIRE 16 -1 (-2075 3900)(-2375 3900);
WIRE 16 -1 (-2075 3725)(-2375 3725);
WIRE 16 -1 (-2375 3900)(-2375 3725);
WIRE 16 -1 (-2100 3875)(-2100 3750);
WIRE 16 -1 (-2100 3875)(-2350 3875);
WIRE 16 -1 (-2350 3750)(-2100 3750);
WIRE 16 -1 (-2350 3875)(-2350 3750);
WIRE 16 -1 (-2300 2050)(-1325 2050);
FORCEPROP 2 LAST SIG_NAME PD_GTL2014_2_VREF
J 0
(-2035 2060);
DISPLAY 0.617021 (-2035 2060);
PAINT ORANGE (-2035 2060);
FORCEPROP 2 LASTPROP $XRERR UNIQUE?
J 0
(-2275 2060);
DISPLAY 0.638298 (-2275 2060);
PAINT MONO (-2275 2060);
DISPLAY INVISIBLE (-2275 2060);
WIRE 16 -1 (-2100 1950)(-1325 1950);
FORCEPROP 2 LAST SIG_NAME PU_GTL2014_2_DIR
J 0
(-2035 1960);
DISPLAY 0.617021 (-2035 1960);
PAINT ORANGE (-2035 1960);
FORCEPROP 2 LASTPROP $XRERR UNIQUE?
J 0
(-2275 1960);
DISPLAY 0.638298 (-2275 1960);
PAINT MONO (-2275 1960);
DISPLAY INVISIBLE (-2275 1960);
WIRE 16 -1 (-2100 2250)(-2100 1950);
WIRE 16 -1 (-1325 4050)(-2150 4050);
FORCEPROP 2 LAST SIG_NAME RST_CPU0_LVC3_N
J 0
(-2085 4060);
DISPLAY 0.617021 (-2085 4060);
PAINT ORANGE (-2085 4060);
WIRE 16 -1 (-1325 1800)(-2150 1800);
FORCEPROP 2 LAST SIG_NAME PWRGD_CPU1_LVC3
J 0
(-2075 1810);
DISPLAY 0.617021 (-2075 1810);
PAINT ORANGE (-2075 1810);
WIRE 16 -1 (-1325 1750)(-2150 1750);
FORCEPROP 2 LAST SIG_NAME RST_CPU1_LVC3_N
J 0
(-2060 1760);
DISPLAY 0.617021 (-2060 1760);
PAINT ORANGE (-2060 1760);
WIRE 16 -1 (-1425 1650)(-1325 1650);
WIRE 16 -1 (-1425 1700)(-1425 1650);
WIRE 16 -1 (-1325 1700)(-1425 1700);
WIRE 16 -1 (-1425 1700)(-2150 1700);
FORCEPROP 2 LAST SIG_NAME PWRGD_DRAMPWRGD
J 0
(-2075 1710);
DISPLAY 0.617021 (-2075 1710);
PAINT ORANGE (-2075 1710);
WIRE 16 -1 (-1425 3950)(-1325 3950);
WIRE 16 -1 (-1425 4000)(-1425 3950);
WIRE 16 -1 (-1325 4000)(-1425 4000);
WIRE 16 -1 (-1425 4000)(-2150 4000);
FORCEPROP 2 LAST SIG_NAME PWRGD_DRAMPWRGD
J 0
(-2075 4010);
DISPLAY 0.617021 (-2075 4010);
PAINT ORANGE (-2075 4010);
WIRE 16 -1 (-2300 4350)(-1325 4350);
FORCEPROP 2 LAST SIG_NAME PD_GTL2014_1_VREF
J 0
(-1885 4360);
DISPLAY 0.617021 (-1885 4360);
PAINT ORANGE (-1885 4360);
FORCEPROP 2 LASTPROP $XRERR UNIQUE?
J 0
(-2125 4360);
DISPLAY 0.638298 (-2125 4360);
PAINT MONO (-2125 4360);
DISPLAY INVISIBLE (-2125 4360);
WIRE 16 -1 (-2100 4250)(-1325 4250);
FORCEPROP 2 LAST SIG_NAME PU_GTL2014_1_DIR
J 0
(-2035 4260);
DISPLAY 0.617021 (-2035 4260);
PAINT ORANGE (-2035 4260);
FORCEPROP 2 LASTPROP $XRERR UNIQUE?
J 0
(-2275 4260);
DISPLAY 0.638298 (-2275 4260);
PAINT MONO (-2275 4260);
DISPLAY INVISIBLE (-2275 4260);
WIRE 16 -1 (-2100 4550)(-2100 4250);
WIRE 16 -1 (-1325 4100)(-2150 4100);
FORCEPROP 2 LAST SIG_NAME PWRGD_CPU0_LVC3
J 0
(-2075 4110);
DISPLAY 0.617021 (-2075 4110);
PAINT ORANGE (-2075 4110);
WIRE 16 273 (-3525 2875)(4250 2875);
WIRE 16 -1 (1900 2050)(1900 1575);
WIRE 16 -1 (3325 1575)(1900 1575);
FORCEPROP 2 LAST SIG_NAME RST_CPU1_G_N
J 0
(2550 1585);
DISPLAY 0.617021 (2550 1585);
PAINT ORANGE (2550 1585);
WIRE 16 -1 (1550 1575)(1900 1575);
WIRE 16 -1 (1550 1750)(1550 1575);
WIRE 16 -1 (-425 1750)(1550 1750);
WIRE 16 -1 (3325 1050)(1075 1050);
FORCEPROP 2 LAST SIG_NAME PWRGD_CPU1_DRAMPWROK_KLM_G
J 0
(2550 1060);
DISPLAY 0.617021 (2550 1060);
PAINT ORANGE (2550 1060);
WIRE 16 -1 (1075 1650)(1075 1050);
WIRE 16 -1 (1075 1650)(975 1650);
WIRE 16 -1 (975 2050)(975 1650);
WIRE 16 -1 (-425 1650)(975 1650);
WIRE 16 -1 (3325 1350)(1250 1350);
FORCEPROP 2 LAST SIG_NAME PWRGD_CPU1_DRAMPWROK_GHJ_G
J 0
(2550 1360);
DISPLAY 0.617021 (2550 1360);
PAINT ORANGE (2550 1360);
WIRE 16 -1 (1250 1350)(1250 1700);
WIRE 16 -1 (1250 1700)(575 1700);
WIRE 16 -1 (575 2050)(575 1700);
WIRE 16 -1 (-425 1700)(575 1700);
WIRE 16 -1 (3325 3875)(1900 3875);
FORCEPROP 2 LAST SIG_NAME RST_CPU0_G_N
J 0
(2550 3885);
DISPLAY 0.617021 (2550 3885);
PAINT ORANGE (2550 3885);
WIRE 16 -1 (1900 4350)(1900 3875);
WIRE 16 -1 (1550 3875)(1900 3875);
WIRE 16 -1 (1550 4050)(1550 3875);
WIRE 16 -1 (-425 4050)(1550 4050);
WIRE 16 2175 (2375 1875)(2375 2775);
WIRE 16 2175 (275 1875)(2375 1875);
WIRE 16 2175 (2375 2775)(275 2775);
WIRE 16 2175 (275 2775)(275 1875);
WIRE 16 -1 (-425 4000)(575 4000);
WIRE 16 -1 (575 4350)(575 4000);
WIRE 16 -1 (1250 4000)(575 4000);
WIRE 16 -1 (1250 3650)(1250 4000);
WIRE 16 -1 (3325 3650)(1250 3650);
FORCEPROP 2 LAST SIG_NAME PWRGD_CPU0_DRAMPWROK_ABC_G
J 0
(2550 3660);
DISPLAY 0.617021 (2550 3660);
PAINT ORANGE (2550 3660);
WIRE 16 -1 (-425 3950)(975 3950);
WIRE 16 -1 (975 4350)(975 3950);
WIRE 16 -1 (1075 3950)(975 3950);
WIRE 16 -1 (1075 3950)(1075 3350);
WIRE 16 -1 (3325 3350)(1075 3350);
FORCEPROP 2 LAST SIG_NAME PWRGD_CPU0_DRAMPWROK_DEF_G
J 0
(2550 3360);
DISPLAY 0.617021 (2550 3360);
PAINT ORANGE (2550 3360);
WIRE 16 -1 (3325 1800)(1700 1800);
FORCEPROP 2 LAST SIG_NAME PWRGD_CPU1_G
J 0
(2550 1810);
DISPLAY 0.617021 (2550 1810);
PAINT ORANGE (2550 1810);
WIRE 16 -1 (1700 2050)(1700 1800);
WIRE 16 -1 (1700 1800)(-425 1800);
WIRE 16 -1 (4050 1425)(4050 1300);
WIRE 16 -1 (4050 1425)(3800 1425);
WIRE 16 -1 (3800 1300)(4050 1300);
WIRE 16 -1 (3800 1425)(3800 1300);
WIRE 16 -1 (4075 1450)(4075 1275);
WIRE 16 -1 (4075 1450)(3775 1450);
WIRE 16 -1 (4075 1275)(3775 1275);
WIRE 16 -1 (3775 1450)(3775 1275);
WIRE 16 -1 (3800 3575)(3800 3450);
WIRE 16 -1 (4050 3575)(3800 3575);
WIRE 16 -1 (3800 3450)(4050 3450);
WIRE 16 -1 (4050 3575)(4050 3450);
WIRE 16 -1 (4075 3600)(3775 3600);
WIRE 16 -1 (4075 3600)(4075 3425);
WIRE 16 -1 (3775 3600)(3775 3425);
WIRE 16 -1 (4075 3425)(3775 3425);
WIRE 16 2175 (2300 4200)(2300 5075);
WIRE 16 2175 (350 4200)(2300 4200);
WIRE 16 2175 (2300 5075)(350 5075);
WIRE 16 2175 (350 5075)(350 4200);
WIRE 16 -1 (3325 4100)(1700 4100);
FORCEPROP 2 LAST SIG_NAME PWRGD_CPU0_G
J 0
(2550 4110);
DISPLAY 0.617021 (2550 4110);
PAINT ORANGE (2550 4110);
WIRE 16 -1 (1700 4350)(1700 4100);
WIRE 16 -1 (1700 4100)(-425 4100);
WIRE 16 -1 (4325 4075)(4325 3900);
WIRE 16 -1 (4325 4075)(3750 4075);
WIRE 16 -1 (4325 3900)(3750 3900);
WIRE 16 -1 (3750 4075)(3750 3900);
WIRE 16 -1 (4300 4050)(4300 3925);
WIRE 16 -1 (4300 4050)(3775 4050);
WIRE 16 -1 (3775 3925)(4300 3925);
WIRE 16 -1 (3775 4050)(3775 3925);
DOT 1 (-2100 4850);
DOT 1 (1800 2300);
DOT 1 (1700 4100);
DOT 1 (-1725 2550);
DOT 1 (-1650 4850);
DOT 1 (-325 3750);
DOT 1 (1900 1575);
DOT 1 (-2100 2550);
DOT 1 (-1425 1700);
DOT 1 (-325 1400);
DOT 1 (-325 1450);
DOT 1 (-1425 4000);
DOT 1 (-325 3700);
DOT 1 (575 1700);
DOT 1 (975 1650);
DOT 1 (1700 1800);
DOT 1 (575 4000);
DOT 1 (975 3950);
DOT 1 (1900 3875);
DOT 1 (1800 4600);
FORCENOTE
TO
(4025 4000) 0;
DISPLAY LEFT (4025 4000);
DISPLAY 0.808511 (4025 4000);
PAINT PURPLE (4025 4000);
FORCENOTE
CPU0/CPU XDP
(3825 3950) 0;
DISPLAY LEFT (3825 3950);
DISPLAY 0.808511 (3825 3950);
PAINT PURPLE (3825 3950);
FORCENOTE
CPU0
(3850 3475) 0;
DISPLAY LEFT (3850 3475);
DISPLAY 0.808511 (3850 3475);
PAINT PURPLE (3850 3475);
FORCENOTE
TO
(3900 3525) 0;
DISPLAY LEFT (3900 3525);
DISPLAY 0.808511 (3900 3525);
PAINT PURPLE (3900 3525);
FORCENOTE
TO
(3900 1375) 0;
DISPLAY LEFT (3900 1375);
DISPLAY 1.021277 (3900 1375);
PAINT PURPLE (3900 1375);
FORCENOTE
CPU1
(3850 1325) 0;
DISPLAY LEFT (3850 1325);
DISPLAY 1.021277 (3850 1325);
PAINT PURPLE (3850 1325);
FORCENOTE
FROM
(-2300 3825) 0;
DISPLAY LEFT (-2300 3825);
DISPLAY 0.808511 (-2300 3825);
PAINT PURPLE (-2300 3825);
FORCENOTE
CPLD
(-2300 3775) 0;
DISPLAY LEFT (-2300 3775);
DISPLAY 0.808511 (-2300 3775);
PAINT PURPLE (-2300 3775);
FORCENOTE
FROM
(-2300 1525) 0;
DISPLAY LEFT (-2300 1525);
DISPLAY 1.021277 (-2300 1525);
PAINT PURPLE (-2300 1525);
FORCENOTE
CPLD
(-2300 1475) 0;
DISPLAY LEFT (-2300 1475);
DISPLAY 1.021277 (-2300 1475);
PAINT PURPLE (-2300 1475);
FORCENOTE
BOM_COST=PROC_SIDEBAND
(-3375 600) 0;
DISPLAY LEFT (-3375 600);
DISPLAY 1.276596 (-3375 600);
PAINT PURPLE (-3375 600);
FORCENOTE
ROOM=PROC_RSTS_PGOODS
(-3375 675) 0;
DISPLAY LEFT (-3375 675);
DISPLAY 1.276596 (-3375 675);
PAINT PURPLE (-3375 675);
QUIT
